(kicad_sch
	(version 20250114)
	(generator "eeschema")
	(generator_version "9.0")
	(paper "A3")
	(title_block
		(title "Thunderbolt to 10GbE adapter")
		(date "2026-04-23")
		(rev "1.1.0")
		(company "Antmicro Ltd")
		(comment 1 "www.antmicro.com")
	)
	(text "10GbE Port 1"
		(exclude_from_sim no)
		(at 215.9 173.99 0)
		(effects
			(font
				(size 2.54 2.54)
				(thickness 0.508)
				(bold yes)
			)
		)
	)
	(text "10GbE Port 0"
		(exclude_from_sim no)
		(at 215.9 38.1 0)
		(effects
			(font
				(size 2.54 2.54)
				(thickness 0.508)
				(bold yes)
			)
		)
	)
	(junction
		(at 154.94 233.68)
		(diameter 0)
		(color 0 0 0 0)
	)
	(junction
		(at 228.6 215.9)
		(diameter 0)
		(color 0 0 0 0)
	)
	(junction
		(at 92.71 97.79)
		(diameter 0)
		(color 0 0 0 0)
	)
	(junction
		(at 194.31 97.79)
		(diameter 0)
		(color 0 0 0 0)
	)
	(junction
		(at 243.84 220.98)
		(diameter 0)
		(color 0 0 0 0)
	)
	(junction
		(at 176.53 233.68)
		(diameter 0)
		(color 0 0 0 0)
	)
	(junction
		(at 233.68 241.3)
		(diameter 0)
		(color 0 0 0 0)
	)
	(junction
		(at 243.84 105.41)
		(diameter 0)
		(color 0 0 0 0)
	)
	(junction
		(at 201.93 231.14)
		(diameter 0)
		(color 0 0 0 0)
	)
	(junction
		(at 167.64 97.79)
		(diameter 0)
		(color 0 0 0 0)
	)
	(junction
		(at 185.42 233.68)
		(diameter 0)
		(color 0 0 0 0)
	)
	(junction
		(at 154.94 97.79)
		(diameter 0)
		(color 0 0 0 0)
	)
	(junction
		(at 201.93 97.79)
		(diameter 0)
		(color 0 0 0 0)
	)
	(junction
		(at 201.93 95.25)
		(diameter 0)
		(color 0 0 0 0)
	)
	(junction
		(at 167.64 233.68)
		(diameter 0)
		(color 0 0 0 0)
	)
	(junction
		(at 228.6 105.41)
		(diameter 0)
		(color 0 0 0 0)
	)
	(junction
		(at 201.93 233.68)
		(diameter 0)
		(color 0 0 0 0)
	)
	(junction
		(at 243.84 241.3)
		(diameter 0)
		(color 0 0 0 0)
	)
	(junction
		(at 254 92.71)
		(diameter 0)
		(color 0 0 0 0)
	)
	(junction
		(at 71.12 97.79)
		(diameter 0)
		(color 0 0 0 0)
	)
	(junction
		(at 233.68 82.55)
		(diameter 0)
		(color 0 0 0 0)
	)
	(junction
		(at 201.93 228.6)
		(diameter 0)
		(color 0 0 0 0)
	)
	(junction
		(at 59.69 97.79)
		(diameter 0)
		(color 0 0 0 0)
	)
	(junction
		(at 194.31 233.68)
		(diameter 0)
		(color 0 0 0 0)
	)
	(junction
		(at 228.6 241.3)
		(diameter 0)
		(color 0 0 0 0)
	)
	(junction
		(at 243.84 85.09)
		(diameter 0)
		(color 0 0 0 0)
	)
	(junction
		(at 86.36 97.79)
		(diameter 0)
		(color 0 0 0 0)
	)
	(junction
		(at 228.6 80.01)
		(diameter 0)
		(color 0 0 0 0)
	)
	(junction
		(at 201.93 92.71)
		(diameter 0)
		(color 0 0 0 0)
	)
	(junction
		(at 254 228.6)
		(diameter 0)
		(color 0 0 0 0)
	)
	(junction
		(at 95.25 97.79)
		(diameter 0)
		(color 0 0 0 0)
	)
	(junction
		(at 233.68 105.41)
		(diameter 0)
		(color 0 0 0 0)
	)
	(junction
		(at 176.53 97.79)
		(diameter 0)
		(color 0 0 0 0)
	)
	(junction
		(at 233.68 218.44)
		(diameter 0)
		(color 0 0 0 0)
	)
	(junction
		(at 185.42 97.79)
		(diameter 0)
		(color 0 0 0 0)
	)
	(bus_entry
		(at 181.61 74.93)
		(size 2.54 2.54)
		(stroke
			(width 0)
			(type default)
		)
	)
	(bus_entry
		(at 181.61 62.23)
		(size 2.54 2.54)
		(stroke
			(width 0)
			(type default)
		)
	)
	(bus_entry
		(at 181.61 77.47)
		(size 2.54 2.54)
		(stroke
			(width 0)
			(type default)
		)
	)
	(bus_entry
		(at 181.61 64.77)
		(size 2.54 2.54)
		(stroke
			(width 0)
			(type default)
		)
	)
	(bus_entry
		(at 181.61 208.28)
		(size 2.54 2.54)
		(stroke
			(width 0)
			(type default)
		)
	)
	(bus_entry
		(at 181.61 72.39)
		(size 2.54 2.54)
		(stroke
			(width 0)
			(type default)
		)
	)
	(bus_entry
		(at 181.61 69.85)
		(size 2.54 2.54)
		(stroke
			(width 0)
			(type default)
		)
	)
	(bus_entry
		(at 181.61 198.12)
		(size 2.54 2.54)
		(stroke
			(width 0)
			(type default)
		)
	)
	(bus_entry
		(at 181.61 210.82)
		(size 2.54 2.54)
		(stroke
			(width 0)
			(type default)
		)
	)
	(bus_entry
		(at 181.61 195.58)
		(size 2.54 2.54)
		(stroke
			(width 0)
			(type default)
		)
	)
	(bus_entry
		(at 181.61 59.69)
		(size 2.54 2.54)
		(stroke
			(width 0)
			(type default)
		)
	)
	(bus_entry
		(at 181.61 67.31)
		(size 2.54 2.54)
		(stroke
			(width 0)
			(type default)
		)
	)
	(bus_entry
		(at 181.61 205.74)
		(size 2.54 2.54)
		(stroke
			(width 0)
			(type default)
		)
	)
	(bus_entry
		(at 181.61 213.36)
		(size 2.54 2.54)
		(stroke
			(width 0)
			(type default)
		)
	)
	(bus_entry
		(at 181.61 203.2)
		(size 2.54 2.54)
		(stroke
			(width 0)
			(type default)
		)
	)
	(bus_entry
		(at 181.61 200.66)
		(size 2.54 2.54)
		(stroke
			(width 0)
			(type default)
		)
	)
	(wire
		(pts
			(xy 243.84 105.41) (xy 233.68 105.41)
		)
		(stroke
			(width 0)
			(type default)
		)
	)
	(bus
		(pts
			(xy 181.61 195.58) (xy 181.61 193.04)
		)
		(stroke
			(width 0)
			(type default)
		)
	)
	(wire
		(pts
			(xy 254 228.6) (xy 259.08 228.6)
		)
		(stroke
			(width 0)
			(type default)
		)
	)
	(wire
		(pts
			(xy 106.68 97.79) (xy 106.68 96.52)
		)
		(stroke
			(width 0)
			(type default)
		)
	)
	(wire
		(pts
			(xy 154.94 97.79) (xy 167.64 97.79)
		)
		(stroke
			(width 0)
			(type default)
		)
	)
	(wire
		(pts
			(xy 228.6 105.41) (xy 233.68 105.41)
		)
		(stroke
			(width 0)
			(type default)
		)
	)
	(bus
		(pts
			(xy 181.61 69.85) (xy 181.61 67.31)
		)
		(stroke
			(width 0)
			(type default)
		)
	)
	(wire
		(pts
			(xy 226.06 218.44) (xy 233.68 218.44)
		)
		(stroke
			(width 0)
			(type default)
		)
	)
	(wire
		(pts
			(xy 185.42 97.79) (xy 185.42 100.33)
		)
		(stroke
			(width 0)
			(type default)
		)
	)
	(wire
		(pts
			(xy 204.47 64.77) (xy 184.15 64.77)
		)
		(stroke
			(width 0)
			(type default)
		)
	)
	(wire
		(pts
			(xy 142.24 233.68) (xy 147.32 233.68)
		)
		(stroke
			(width 0)
			(type default)
		)
	)
	(wire
		(pts
			(xy 95.25 105.41) (xy 95.25 107.95)
		)
		(stroke
			(width 0)
			(type default)
		)
	)
	(wire
		(pts
			(xy 167.64 233.68) (xy 176.53 233.68)
		)
		(stroke
			(width 0)
			(type default)
		)
	)
	(wire
		(pts
			(xy 194.31 233.68) (xy 194.31 236.22)
		)
		(stroke
			(width 0)
			(type default)
		)
	)
	(bus
		(pts
			(xy 179.07 54.61) (xy 181.61 57.15)
		)
		(stroke
			(width 0)
			(type default)
		)
	)
	(wire
		(pts
			(xy 106.68 97.79) (xy 95.25 97.79)
		)
		(stroke
			(width 0)
			(type default)
		)
	)
	(bus
		(pts
			(xy 179.07 190.5) (xy 181.61 193.04)
		)
		(stroke
			(width 0)
			(type default)
		)
	)
	(bus
		(pts
			(xy 181.61 74.93) (xy 181.61 72.39)
		)
		(stroke
			(width 0)
			(type default)
		)
	)
	(wire
		(pts
			(xy 204.47 213.36) (xy 184.15 213.36)
		)
		(stroke
			(width 0)
			(type default)
		)
	)
	(bus
		(pts
			(xy 181.61 67.31) (xy 181.61 64.77)
		)
		(stroke
			(width 0)
			(type default)
		)
	)
	(wire
		(pts
			(xy 204.47 77.47) (xy 184.15 77.47)
		)
		(stroke
			(width 0)
			(type default)
		)
	)
	(wire
		(pts
			(xy 264.16 82.55) (xy 271.78 82.55)
		)
		(stroke
			(width 0)
			(type default)
		)
	)
	(bus
		(pts
			(xy 181.61 77.47) (xy 181.61 74.93)
		)
		(stroke
			(width 0)
			(type default)
		)
	)
	(bus
		(pts
			(xy 181.61 213.36) (xy 181.61 210.82)
		)
		(stroke
			(width 0)
			(type default)
		)
	)
	(wire
		(pts
			(xy 142.24 95.25) (xy 142.24 97.79)
		)
		(stroke
			(width 0)
			(type default)
		)
	)
	(wire
		(pts
			(xy 167.64 105.41) (xy 167.64 107.95)
		)
		(stroke
			(width 0)
			(type default)
		)
	)
	(wire
		(pts
			(xy 243.84 220.98) (xy 259.08 220.98)
		)
		(stroke
			(width 0)
			(type default)
		)
	)
	(wire
		(pts
			(xy 142.24 97.79) (xy 147.32 97.79)
		)
		(stroke
			(width 0)
			(type default)
		)
	)
	(wire
		(pts
			(xy 226.06 226.06) (xy 228.6 226.06)
		)
		(stroke
			(width 0)
			(type default)
		)
	)
	(wire
		(pts
			(xy 233.68 238.76) (xy 233.68 241.3)
		)
		(stroke
			(width 0)
			(type default)
		)
	)
	(wire
		(pts
			(xy 264.16 85.09) (xy 271.78 85.09)
		)
		(stroke
			(width 0)
			(type default)
		)
	)
	(wire
		(pts
			(xy 154.94 97.79) (xy 154.94 100.33)
		)
		(stroke
			(width 0)
			(type default)
		)
	)
	(wire
		(pts
			(xy 154.94 233.68) (xy 154.94 236.22)
		)
		(stroke
			(width 0)
			(type default)
		)
	)
	(wire
		(pts
			(xy 167.64 236.22) (xy 167.64 233.68)
		)
		(stroke
			(width 0)
			(type default)
		)
	)
	(wire
		(pts
			(xy 226.06 215.9) (xy 228.6 215.9)
		)
		(stroke
			(width 0)
			(type default)
		)
	)
	(wire
		(pts
			(xy 228.6 215.9) (xy 228.6 213.36)
		)
		(stroke
			(width 0)
			(type default)
		)
	)
	(wire
		(pts
			(xy 233.68 218.44) (xy 233.68 233.68)
		)
		(stroke
			(width 0)
			(type default)
		)
	)
	(wire
		(pts
			(xy 226.06 92.71) (xy 254 92.71)
		)
		(stroke
			(width 0)
			(type default)
		)
	)
	(wire
		(pts
			(xy 243.84 102.87) (xy 243.84 105.41)
		)
		(stroke
			(width 0)
			(type default)
		)
	)
	(wire
		(pts
			(xy 59.69 97.79) (xy 71.12 97.79)
		)
		(stroke
			(width 0)
			(type default)
		)
	)
	(wire
		(pts
			(xy 81.28 97.79) (xy 86.36 97.79)
		)
		(stroke
			(width 0)
			(type default)
		)
	)
	(wire
		(pts
			(xy 71.12 97.79) (xy 71.12 100.33)
		)
		(stroke
			(width 0)
			(type default)
		)
	)
	(wire
		(pts
			(xy 59.69 97.79) (xy 59.69 100.33)
		)
		(stroke
			(width 0)
			(type default)
		)
	)
	(wire
		(pts
			(xy 204.47 208.28) (xy 184.15 208.28)
		)
		(stroke
			(width 0)
			(type default)
		)
	)
	(wire
		(pts
			(xy 201.93 233.68) (xy 204.47 233.68)
		)
		(stroke
			(width 0)
			(type default)
		)
	)
	(wire
		(pts
			(xy 264.16 228.6) (xy 271.78 228.6)
		)
		(stroke
			(width 0)
			(type default)
		)
	)
	(wire
		(pts
			(xy 86.36 97.79) (xy 92.71 97.79)
		)
		(stroke
			(width 0)
			(type default)
		)
	)
	(wire
		(pts
			(xy 226.06 233.68) (xy 228.6 233.68)
		)
		(stroke
			(width 0)
			(type default)
		)
	)
	(wire
		(pts
			(xy 92.71 97.79) (xy 95.25 97.79)
		)
		(stroke
			(width 0)
			(type default)
		)
	)
	(wire
		(pts
			(xy 185.42 233.68) (xy 194.31 233.68)
		)
		(stroke
			(width 0)
			(type default)
		)
	)
	(wire
		(pts
			(xy 233.68 82.55) (xy 259.08 82.55)
		)
		(stroke
			(width 0)
			(type default)
		)
	)
	(wire
		(pts
			(xy 226.06 97.79) (xy 228.6 97.79)
		)
		(stroke
			(width 0)
			(type default)
		)
	)
	(wire
		(pts
			(xy 201.93 231.14) (xy 201.93 228.6)
		)
		(stroke
			(width 0)
			(type default)
		)
	)
	(wire
		(pts
			(xy 243.84 241.3) (xy 233.68 241.3)
		)
		(stroke
			(width 0)
			(type default)
		)
	)
	(wire
		(pts
			(xy 86.36 97.79) (xy 86.36 100.33)
		)
		(stroke
			(width 0)
			(type default)
		)
	)
	(wire
		(pts
			(xy 243.84 238.76) (xy 243.84 241.3)
		)
		(stroke
			(width 0)
			(type default)
		)
	)
	(wire
		(pts
			(xy 254 241.3) (xy 243.84 241.3)
		)
		(stroke
			(width 0)
			(type default)
		)
	)
	(wire
		(pts
			(xy 204.47 90.17) (xy 201.93 90.17)
		)
		(stroke
			(width 0)
			(type default)
		)
	)
	(bus
		(pts
			(xy 181.61 62.23) (xy 181.61 59.69)
		)
		(stroke
			(width 0)
			(type default)
		)
	)
	(wire
		(pts
			(xy 204.47 198.12) (xy 184.15 198.12)
		)
		(stroke
			(width 0)
			(type default)
		)
	)
	(wire
		(pts
			(xy 201.93 228.6) (xy 204.47 228.6)
		)
		(stroke
			(width 0)
			(type default)
		)
	)
	(wire
		(pts
			(xy 204.47 203.2) (xy 184.15 203.2)
		)
		(stroke
			(width 0)
			(type default)
		)
	)
	(wire
		(pts
			(xy 204.47 205.74) (xy 184.15 205.74)
		)
		(stroke
			(width 0)
			(type default)
		)
	)
	(wire
		(pts
			(xy 154.94 233.68) (xy 167.64 233.68)
		)
		(stroke
			(width 0)
			(type default)
		)
	)
	(bus
		(pts
			(xy 181.61 72.39) (xy 181.61 69.85)
		)
		(stroke
			(width 0)
			(type default)
		)
	)
	(wire
		(pts
			(xy 233.68 102.87) (xy 233.68 105.41)
		)
		(stroke
			(width 0)
			(type default)
		)
	)
	(wire
		(pts
			(xy 204.47 215.9) (xy 184.15 215.9)
		)
		(stroke
			(width 0)
			(type default)
		)
	)
	(wire
		(pts
			(xy 254 92.71) (xy 259.08 92.71)
		)
		(stroke
			(width 0)
			(type default)
		)
	)
	(wire
		(pts
			(xy 152.4 233.68) (xy 154.94 233.68)
		)
		(stroke
			(width 0)
			(type default)
		)
	)
	(wire
		(pts
			(xy 204.47 67.31) (xy 184.15 67.31)
		)
		(stroke
			(width 0)
			(type default)
		)
	)
	(wire
		(pts
			(xy 185.42 233.68) (xy 185.42 236.22)
		)
		(stroke
			(width 0)
			(type default)
		)
	)
	(wire
		(pts
			(xy 185.42 105.41) (xy 185.42 107.95)
		)
		(stroke
			(width 0)
			(type default)
		)
	)
	(wire
		(pts
			(xy 176.53 241.3) (xy 176.53 243.84)
		)
		(stroke
			(width 0)
			(type default)
		)
	)
	(wire
		(pts
			(xy 201.93 228.6) (xy 201.93 226.06)
		)
		(stroke
			(width 0)
			(type default)
		)
	)
	(wire
		(pts
			(xy 185.42 241.3) (xy 185.42 243.84)
		)
		(stroke
			(width 0)
			(type default)
		)
	)
	(wire
		(pts
			(xy 243.84 220.98) (xy 243.84 233.68)
		)
		(stroke
			(width 0)
			(type default)
		)
	)
	(wire
		(pts
			(xy 264.16 92.71) (xy 271.78 92.71)
		)
		(stroke
			(width 0)
			(type default)
		)
	)
	(wire
		(pts
			(xy 264.16 220.98) (xy 271.78 220.98)
		)
		(stroke
			(width 0)
			(type default)
		)
	)
	(wire
		(pts
			(xy 204.47 200.66) (xy 184.15 200.66)
		)
		(stroke
			(width 0)
			(type default)
		)
	)
	(wire
		(pts
			(xy 71.12 105.41) (xy 71.12 107.95)
		)
		(stroke
			(width 0)
			(type default)
		)
	)
	(wire
		(pts
			(xy 254 228.6) (xy 254 233.68)
		)
		(stroke
			(width 0)
			(type default)
		)
	)
	(wire
		(pts
			(xy 176.53 105.41) (xy 176.53 107.95)
		)
		(stroke
			(width 0)
			(type default)
		)
	)
	(wire
		(pts
			(xy 228.6 241.3) (xy 228.6 243.84)
		)
		(stroke
			(width 0)
			(type default)
		)
	)
	(wire
		(pts
			(xy 226.06 82.55) (xy 233.68 82.55)
		)
		(stroke
			(width 0)
			(type default)
		)
	)
	(wire
		(pts
			(xy 228.6 241.3) (xy 233.68 241.3)
		)
		(stroke
			(width 0)
			(type default)
		)
	)
	(wire
		(pts
			(xy 204.47 69.85) (xy 184.15 69.85)
		)
		(stroke
			(width 0)
			(type default)
		)
	)
	(bus
		(pts
			(xy 181.61 64.77) (xy 181.61 62.23)
		)
		(stroke
			(width 0)
			(type default)
		)
	)
	(bus
		(pts
			(xy 181.61 200.66) (xy 181.61 198.12)
		)
		(stroke
			(width 0)
			(type default)
		)
	)
	(bus
		(pts
			(xy 179.07 54.61) (xy 176.53 54.61)
		)
		(stroke
			(width 0)
			(type default)
		)
	)
	(wire
		(pts
			(xy 92.71 95.25) (xy 92.71 97.79)
		)
		(stroke
			(width 0)
			(type default)
		)
	)
	(wire
		(pts
			(xy 204.47 80.01) (xy 184.15 80.01)
		)
		(stroke
			(width 0)
			(type default)
		)
	)
	(wire
		(pts
			(xy 201.93 231.14) (xy 204.47 231.14)
		)
		(stroke
			(width 0)
			(type default)
		)
	)
	(wire
		(pts
			(xy 228.6 215.9) (xy 228.6 226.06)
		)
		(stroke
			(width 0)
			(type default)
		)
	)
	(wire
		(pts
			(xy 59.69 105.41) (xy 59.69 107.95)
		)
		(stroke
			(width 0)
			(type default)
		)
	)
	(wire
		(pts
			(xy 201.93 97.79) (xy 201.93 95.25)
		)
		(stroke
			(width 0)
			(type default)
		)
	)
	(wire
		(pts
			(xy 176.53 97.79) (xy 176.53 100.33)
		)
		(stroke
			(width 0)
			(type default)
		)
	)
	(bus
		(pts
			(xy 181.61 208.28) (xy 181.61 205.74)
		)
		(stroke
			(width 0)
			(type default)
		)
	)
	(wire
		(pts
			(xy 254 92.71) (xy 254 97.79)
		)
		(stroke
			(width 0)
			(type default)
		)
	)
	(wire
		(pts
			(xy 226.06 85.09) (xy 243.84 85.09)
		)
		(stroke
			(width 0)
			(type default)
		)
	)
	(bus
		(pts
			(xy 181.61 198.12) (xy 181.61 195.58)
		)
		(stroke
			(width 0)
			(type default)
		)
	)
	(polyline
		(pts
			(xy 12.7 143.51) (xy 407.67 143.51)
		)
		(stroke
			(width 0)
			(type dash)
		)
	)
	(wire
		(pts
			(xy 228.6 233.68) (xy 228.6 241.3)
		)
		(stroke
			(width 0)
			(type default)
		)
	)
	(wire
		(pts
			(xy 194.31 105.41) (xy 194.31 107.95)
		)
		(stroke
			(width 0)
			(type default)
		)
	)
	(wire
		(pts
			(xy 185.42 97.79) (xy 194.31 97.79)
		)
		(stroke
			(width 0)
			(type default)
		)
	)
	(wire
		(pts
			(xy 76.2 97.79) (xy 71.12 97.79)
		)
		(stroke
			(width 0)
			(type default)
		)
	)
	(wire
		(pts
			(xy 254 105.41) (xy 243.84 105.41)
		)
		(stroke
			(width 0)
			(type default)
		)
	)
	(wire
		(pts
			(xy 228.6 80.01) (xy 228.6 77.47)
		)
		(stroke
			(width 0)
			(type default)
		)
	)
	(wire
		(pts
			(xy 254 102.87) (xy 254 105.41)
		)
		(stroke
			(width 0)
			(type default)
		)
	)
	(wire
		(pts
			(xy 167.64 97.79) (xy 176.53 97.79)
		)
		(stroke
			(width 0)
			(type default)
		)
	)
	(bus
		(pts
			(xy 181.61 205.74) (xy 181.61 203.2)
		)
		(stroke
			(width 0)
			(type default)
		)
	)
	(wire
		(pts
			(xy 194.31 233.68) (xy 201.93 233.68)
		)
		(stroke
			(width 0)
			(type default)
		)
	)
	(wire
		(pts
			(xy 201.93 95.25) (xy 204.47 95.25)
		)
		(stroke
			(width 0)
			(type default)
		)
	)
	(wire
		(pts
			(xy 176.53 97.79) (xy 185.42 97.79)
		)
		(stroke
			(width 0)
			(type default)
		)
	)
	(wire
		(pts
			(xy 167.64 100.33) (xy 167.64 97.79)
		)
		(stroke
			(width 0)
			(type default)
		)
	)
	(wire
		(pts
			(xy 226.06 80.01) (xy 228.6 80.01)
		)
		(stroke
			(width 0)
			(type default)
		)
	)
	(wire
		(pts
			(xy 176.53 233.68) (xy 185.42 233.68)
		)
		(stroke
			(width 0)
			(type default)
		)
	)
	(wire
		(pts
			(xy 204.47 226.06) (xy 201.93 226.06)
		)
		(stroke
			(width 0)
			(type default)
		)
	)
	(wire
		(pts
			(xy 176.53 233.68) (xy 176.53 236.22)
		)
		(stroke
			(width 0)
			(type default)
		)
	)
	(wire
		(pts
			(xy 204.47 62.23) (xy 184.15 62.23)
		)
		(stroke
			(width 0)
			(type default)
		)
	)
	(wire
		(pts
			(xy 86.36 105.41) (xy 86.36 107.95)
		)
		(stroke
			(width 0)
			(type default)
		)
	)
	(wire
		(pts
			(xy 226.06 228.6) (xy 254 228.6)
		)
		(stroke
			(width 0)
			(type default)
		)
	)
	(wire
		(pts
			(xy 59.69 95.25) (xy 59.69 97.79)
		)
		(stroke
			(width 0)
			(type default)
		)
	)
	(wire
		(pts
			(xy 226.06 220.98) (xy 243.84 220.98)
		)
		(stroke
			(width 0)
			(type default)
		)
	)
	(wire
		(pts
			(xy 201.93 233.68) (xy 201.93 231.14)
		)
		(stroke
			(width 0)
			(type default)
		)
	)
	(wire
		(pts
			(xy 228.6 80.01) (xy 228.6 90.17)
		)
		(stroke
			(width 0)
			(type default)
		)
	)
	(wire
		(pts
			(xy 194.31 97.79) (xy 194.31 100.33)
		)
		(stroke
			(width 0)
			(type default)
		)
	)
	(wire
		(pts
			(xy 243.84 85.09) (xy 259.08 85.09)
		)
		(stroke
			(width 0)
			(type default)
		)
	)
	(wire
		(pts
			(xy 201.93 92.71) (xy 204.47 92.71)
		)
		(stroke
			(width 0)
			(type default)
		)
	)
	(wire
		(pts
			(xy 142.24 231.14) (xy 142.24 233.68)
		)
		(stroke
			(width 0)
			(type default)
		)
	)
	(wire
		(pts
			(xy 204.47 74.93) (xy 184.15 74.93)
		)
		(stroke
			(width 0)
			(type default)
		)
	)
	(wire
		(pts
			(xy 201.93 97.79) (xy 204.47 97.79)
		)
		(stroke
			(width 0)
			(type default)
		)
	)
	(wire
		(pts
			(xy 264.16 218.44) (xy 271.78 218.44)
		)
		(stroke
			(width 0)
			(type default)
		)
	)
	(bus
		(pts
			(xy 181.61 210.82) (xy 181.61 208.28)
		)
		(stroke
			(width 0)
			(type default)
		)
	)
	(wire
		(pts
			(xy 194.31 97.79) (xy 201.93 97.79)
		)
		(stroke
			(width 0)
			(type default)
		)
	)
	(wire
		(pts
			(xy 201.93 92.71) (xy 201.93 90.17)
		)
		(stroke
			(width 0)
			(type default)
		)
	)
	(bus
		(pts
			(xy 181.61 203.2) (xy 181.61 200.66)
		)
		(stroke
			(width 0)
			(type default)
		)
	)
	(wire
		(pts
			(xy 243.84 85.09) (xy 243.84 97.79)
		)
		(stroke
			(width 0)
			(type default)
		)
	)
	(wire
		(pts
			(xy 204.47 210.82) (xy 184.15 210.82)
		)
		(stroke
			(width 0)
			(type default)
		)
	)
	(wire
		(pts
			(xy 152.4 97.79) (xy 154.94 97.79)
		)
		(stroke
			(width 0)
			(type default)
		)
	)
	(wire
		(pts
			(xy 154.94 241.3) (xy 154.94 243.84)
		)
		(stroke
			(width 0)
			(type default)
		)
	)
	(wire
		(pts
			(xy 228.6 97.79) (xy 228.6 105.41)
		)
		(stroke
			(width 0)
			(type default)
		)
	)
	(wire
		(pts
			(xy 204.47 72.39) (xy 184.15 72.39)
		)
		(stroke
			(width 0)
			(type default)
		)
	)
	(bus
		(pts
			(xy 179.07 190.5) (xy 176.53 190.5)
		)
		(stroke
			(width 0)
			(type default)
		)
	)
	(wire
		(pts
			(xy 233.68 82.55) (xy 233.68 97.79)
		)
		(stroke
			(width 0)
			(type default)
		)
	)
	(wire
		(pts
			(xy 201.93 92.71) (xy 201.93 95.25)
		)
		(stroke
			(width 0)
			(type default)
		)
	)
	(wire
		(pts
			(xy 254 238.76) (xy 254 241.3)
		)
		(stroke
			(width 0)
			(type default)
		)
	)
	(wire
		(pts
			(xy 228.6 105.41) (xy 228.6 107.95)
		)
		(stroke
			(width 0)
			(type default)
		)
	)
	(wire
		(pts
			(xy 95.25 97.79) (xy 95.25 100.33)
		)
		(stroke
			(width 0)
			(type default)
		)
	)
	(wire
		(pts
			(xy 233.68 218.44) (xy 259.08 218.44)
		)
		(stroke
			(width 0)
			(type default)
		)
	)
	(wire
		(pts
			(xy 154.94 105.41) (xy 154.94 107.95)
		)
		(stroke
			(width 0)
			(type default)
		)
	)
	(bus
		(pts
			(xy 181.61 59.69) (xy 181.61 57.15)
		)
		(stroke
			(width 0)
			(type default)
		)
	)
	(wire
		(pts
			(xy 167.64 241.3) (xy 167.64 243.84)
		)
		(stroke
			(width 0)
			(type default)
		)
	)
	(wire
		(pts
			(xy 194.31 241.3) (xy 194.31 243.84)
		)
		(stroke
			(width 0)
			(type default)
		)
	)
	(wire
		(pts
			(xy 226.06 90.17) (xy 228.6 90.17)
		)
		(stroke
			(width 0)
			(type default)
		)
	)
	(label "Ethernet_P0.D3+"
		(at 201.93 67.31 180)
		(effects
			(font
				(size 1.27 1.27)
			)
			(justify right bottom)
		)
	)
	(label "P1_CT"
		(at 200.66 233.68 180)
		(effects
			(font
				(size 1.27 1.27)
			)
			(justify right bottom)
		)
	)
	(label "Ethernet_P0.D2-"
		(at 201.93 74.93 180)
		(effects
			(font
				(size 1.27 1.27)
			)
			(justify right bottom)
		)
	)
	(label "Ethernet_P0.D1+"
		(at 201.93 77.47 180)
		(effects
			(font
				(size 1.27 1.27)
			)
			(justify right bottom)
		)
	)
	(label "Ethernet_P1.D4-"
		(at 201.93 215.9 180)
		(effects
			(font
				(size 1.27 1.27)
			)
			(justify right bottom)
		)
	)
	(label "P0_CT"
		(at 200.66 97.79 180)
		(effects
			(font
				(size 1.27 1.27)
			)
			(justify right bottom)
		)
	)
	(label "Ethernet_P1.D3-"
		(at 201.93 210.82 180)
		(effects
			(font
				(size 1.27 1.27)
			)
			(justify right bottom)
		)
	)
	(label "Ethernet_P1.D2+"
		(at 201.93 203.2 180)
		(effects
			(font
				(size 1.27 1.27)
			)
			(justify right bottom)
		)
	)
	(label "Ethernet_P1.D2-"
		(at 201.93 205.74 180)
		(effects
			(font
				(size 1.27 1.27)
			)
			(justify right bottom)
		)
	)
	(label "Ethernet_P1.D1+"
		(at 201.93 198.12 180)
		(effects
			(font
				(size 1.27 1.27)
			)
			(justify right bottom)
		)
	)
	(label "Ethernet_P0.D3-"
		(at 201.93 69.85 180)
		(effects
			(font
				(size 1.27 1.27)
			)
			(justify right bottom)
		)
	)
	(label "Ethernet_P0.D4-"
		(at 201.93 64.77 180)
		(effects
			(font
				(size 1.27 1.27)
			)
			(justify right bottom)
		)
	)
	(label "Ethernet_P1.D1-"
		(at 201.93 200.66 180)
		(effects
			(font
				(size 1.27 1.27)
			)
			(justify right bottom)
		)
	)
	(label "Ethernet_P0.D4+"
		(at 201.93 62.23 180)
		(effects
			(font
				(size 1.27 1.27)
			)
			(justify right bottom)
		)
	)
	(label "Ethernet_P0.D2+"
		(at 201.93 72.39 180)
		(effects
			(font
				(size 1.27 1.27)
			)
			(justify right bottom)
		)
	)
	(label "Ethernet_P0.D1-"
		(at 201.93 80.01 180)
		(effects
			(font
				(size 1.27 1.27)
			)
			(justify right bottom)
		)
	)
	(label "Ethernet_P1.D3+"
		(at 201.93 208.28 180)
		(effects
			(font
				(size 1.27 1.27)
			)
			(justify right bottom)
		)
	)
	(label "Ethernet_P1.D4+"
		(at 201.93 213.36 180)
		(effects
			(font
				(size 1.27 1.27)
			)
			(justify right bottom)
		)
	)
	(hierarchical_label "Ethernet_P1{10GbE}"
		(shape bidirectional)
		(at 176.53 190.5 180)
		(effects
			(font
				(size 1.27 1.27)
			)
			(justify right)
		)
	)
	(hierarchical_label "~{P0_LED_LINK_10G}"
		(shape input)
		(at 271.78 85.09 0)
		(effects
			(font
				(size 1.27 1.27)
			)
			(justify left)
		)
	)
	(hierarchical_label "~{P1_LED_ACT}"
		(shape input)
		(at 271.78 228.6 0)
		(effects
			(font
				(size 1.27 1.27)
			)
			(justify left)
		)
	)
	(hierarchical_label "~{P0_LED_ACT}"
		(shape input)
		(at 271.78 92.71 0)
		(effects
			(font
				(size 1.27 1.27)
			)
			(justify left)
		)
	)
	(hierarchical_label "~{P1_LED_LINK_10G}"
		(shape input)
		(at 271.78 220.98 0)
		(effects
			(font
				(size 1.27 1.27)
			)
			(justify left)
		)
	)
	(hierarchical_label "Ethernet_P0{10GbE}"
		(shape bidirectional)
		(at 176.53 54.61 180)
		(effects
			(font
				(size 1.27 1.27)
			)
			(justify right)
		)
	)
	(hierarchical_label "~{P1_LINK_LESS_THAN_10G}"
		(shape input)
		(at 271.78 218.44 0)
		(effects
			(font
				(size 1.27 1.27)
			)
			(justify left)
		)
	)
	(hierarchical_label "~{P0_LINK_LESS_THAN_10G}"
		(shape input)
		(at 271.78 82.55 0)
		(effects
			(font
				(size 1.27 1.27)
			)
			(justify left)
		)
	)
	(symbol
		(lib_id "antmicropower:GND")
		(at 176.53 243.84 0)
		(unit 1)
		(exclude_from_sim no)
		(in_bom yes)
		(on_board yes)
		(dnp no)
		(property "Reference" "#PWR0442"
			(at 185.42 246.38 0)
			(effects
				(font
					(size 1.27 1.27)
					(thickness 0.15)
				)
				(justify left bottom)
				(hide yes)
			)
		)
		(property "Value" "GND"
			(at 176.53 247.65 0)
			(effects
				(font
					(size 1.27 1.27)
					(thickness 0.15)
				)
			)
		)
		(property "Footprint" ""
			(at 185.42 251.46 0)
			(effects
				(font
					(size 1.27 1.27)
					(thickness 0.15)
				)
				(justify left bottom)
				(hide yes)
			)
		)
		(property "Datasheet" ""
			(at 185.42 256.54 0)
			(effects
				(font
					(size 1.27 1.27)
					(thickness 0.15)
				)
				(justify left bottom)
				(hide yes)
			)
		)
		(property "Description" ""
			(at 176.53 243.84 0)
			(effects
				(font
					(size 1.27 1.27)
				)
				(hide yes)
			)
		)
		(property "Author" "Antmicro"
			(at 185.42 251.46 0)
			(effects
				(font
					(size 1.27 1.27)
					(thickness 0.15)
				)
				(justify left bottom)
				(hide yes)
			)
		)
		(property "License" "Apache-2.0"
			(at 185.42 254 0)
			(effects
				(font
					(size 1.27 1.27)
					(thickness 0.15)
				)
				(justify left bottom)
				(hide yes)
			)
		)
		(pin "1"
		)
		(instances
			(project "OCuLink to 10GbE adapter"
				(path ""
					(reference "#PWR085")
					(unit 1)
				)
			)
			(project "thunderbolt-to-10gbe-adapter"
				(path ""
					(reference "#PWR0442")
					(unit 1)
				)
			)
		)
	)
	(symbol
		(lib_id "antmicroResistors0402:R_220R_0402")
		(at 259.08 85.09 0)
		(unit 1)
		(exclude_from_sim no)
		(in_bom yes)
		(on_board yes)
		(dnp no)
		(property "Reference" "R211"
			(at 259.08 83.82 0)
			(effects
				(font
					(size 1.27 1.27)
					(thickness 0.15)
				)
				(justify right)
			)
		)
		(property "Value" "R_220R_0402"
			(at 279.4 97.79 0)
			(effects
				(font
					(size 1.27 1.27)
					(thickness 0.15)
				)
				(justify left bottom)
				(hide yes)
			)
		)
		(property "Footprint" "antmicro-footprints:R_0402_1005Metric"
			(at 279.4 100.33 0)
			(effects
				(font
					(size 1.27 1.27)
					(thickness 0.15)
				)
				(justify left bottom)
				(hide yes)
			)
		)
		(property "Datasheet" "https://www.bourns.com/docs/product-datasheets/cr.pdf"
			(at 279.4 102.87 0)
			(effects
				(font
					(size 1.27 1.27)
					(thickness 0.15)
				)
				(justify left bottom)
				(hide yes)
			)
		)
		(property "Description" "SMD Chip Resistor, 220 ohm, ± 1%, 62.5 mW, 0402 [1005 Metric], Thick Film, General Purpose"
			(at 259.08 85.09 0)
			(effects
				(font
					(size 1.27 1.27)
				)
				(hide yes)
			)
		)
		(property "MPN" "CR0402-FX-2200GLF"
			(at 279.4 105.41 0)
			(effects
				(font
					(size 1.27 1.27)
					(thickness 0.15)
				)
				(justify left bottom)
				(hide yes)
			)
		)
		(property "Manufacturer" "Bourns"
			(at 279.4 107.95 0)
			(effects
				(font
					(size 1.27 1.27)
					(thickness 0.15)
				)
				(justify left bottom)
				(hide yes)
			)
		)
		(property "License" "Apache-2.0"
			(at 279.4 110.49 0)
			(effects
				(font
					(size 1.27 1.27)
					(thickness 0.15)
				)
				(justify left bottom)
				(hide yes)
			)
		)
		(property "Author" "Antmicro"
			(at 279.4 113.03 0)
			(effects
				(font
					(size 1.27 1.27)
					(thickness 0.15)
				)
				(justify left bottom)
				(hide yes)
			)
		)
		(property "Val" "220R"
			(at 264.16 83.82 0)
			(effects
				(font
					(size 1.27 1.27)
					(thickness 0.15)
				)
				(justify left)
			)
		)
		(property "Tolerance" "1%"
			(at 279.4 95.25 0)
			(effects
				(font
					(size 1.27 1.27)
				)
				(justify left bottom)
				(hide yes)
			)
		)
		(pin "1"
		)
		(pin "2"
		)
		(instances
			(project "OCuLink to 10GbE adapter"
				(path ""
					(reference "R37")
					(unit 1)
				)
			)
			(project "thunderbolt-to-10gbe-adapter"
				(path ""
					(reference "R211")
					(unit 1)
				)
			)
		)
	)
	(symbol
		(lib_id "antmicropower:GND")
		(at 228.6 107.95 0)
		(unit 1)
		(exclude_from_sim no)
		(in_bom yes)
		(on_board yes)
		(dnp no)
		(property "Reference" "#PWR0448"
			(at 237.49 110.49 0)
			(effects
				(font
					(size 1.27 1.27)
					(thickness 0.15)
				)
				(justify left bottom)
				(hide yes)
			)
		)
		(property "Value" "GND"
			(at 228.6 111.76 0)
			(effects
				(font
					(size 1.27 1.27)
					(thickness 0.15)
				)
			)
		)
		(property "Footprint" ""
			(at 237.49 115.57 0)
			(effects
				(font
					(size 1.27 1.27)
					(thickness 0.15)
				)
				(justify left bottom)
				(hide yes)
			)
		)
		(property "Datasheet" ""
			(at 237.49 120.65 0)
			(effects
				(font
					(size 1.27 1.27)
					(thickness 0.15)
				)
				(justify left bottom)
				(hide yes)
			)
		)
		(property "Description" ""
			(at 228.6 107.95 0)
			(effects
				(font
					(size 1.27 1.27)
				)
				(hide yes)
			)
		)
		(property "Author" "Antmicro"
			(at 237.49 115.57 0)
			(effects
				(font
					(size 1.27 1.27)
					(thickness 0.15)
				)
				(justify left bottom)
				(hide yes)
			)
		)
		(property "License" "Apache-2.0"
			(at 237.49 118.11 0)
			(effects
				(font
					(size 1.27 1.27)
					(thickness 0.15)
				)
				(justify left bottom)
				(hide yes)
			)
		)
		(pin "1"
		)
		(instances
			(project "OCuLink to 10GbE adapter"
				(path ""
					(reference "#PWR079")
					(unit 1)
				)
			)
			(project "thunderbolt-to-10gbe-adapter"
				(path ""
					(reference "#PWR0448")
					(unit 1)
				)
			)
		)
	)
	(symbol
		(lib_id "antmicroCapacitors0402:C_1u_25V_0402")
		(at 185.42 105.41 90)
		(unit 1)
		(exclude_from_sim no)
		(in_bom yes)
		(on_board yes)
		(dnp no)
		(property "Reference" "C298"
			(at 187.452 101.6 90)
			(effects
				(font
					(size 1.27 1.27)
					(thickness 0.15)
				)
				(justify right)
			)
		)
		(property "Value" "C_1u_25V_0402"
			(at 195.58 85.09 0)
			(effects
				(font
					(size 1.27 1.27)
					(thickness 0.15)
				)
				(justify left bottom)
				(hide yes)
			)
		)
		(property "Footprint" "antmicro-footprints:C_0402_1005Metric"
			(at 198.12 85.09 0)
			(effects
				(font
					(size 1.27 1.27)
					(thickness 0.15)
				)
				(justify left bottom)
				(hide yes)
			)
		)
		(property "Datasheet" "https://www.murata.com/products/productdetail?partno=GRM155R61E105KE11%23"
			(at 200.66 85.09 0)
			(effects
				(font
					(size 1.27 1.27)
					(thickness 0.15)
				)
				(justify left bottom)
				(hide yes)
			)
		)
		(property "Description" "SMD Multilayer Ceramic Capacitor, 1 µF, 25 V, 0402 [1005 Metric], ± 10%, X5R, GRM Series"
			(at 185.42 105.41 0)
			(effects
				(font
					(size 1.27 1.27)
				)
				(hide yes)
			)
		)
		(property "MPN" "GRM155R61E105KE11J"
			(at 203.2 85.09 0)
			(effects
				(font
					(size 1.27 1.27)
					(thickness 0.15)
				)
				(justify left bottom)
				(hide yes)
			)
		)
		(property "Manufacturer" "Murata"
			(at 205.74 85.09 0)
			(effects
				(font
					(size 1.27 1.27)
					(thickness 0.15)
				)
				(justify left bottom)
				(hide yes)
			)
		)
		(property "License" "Apache-2.0"
			(at 208.28 85.09 0)
			(effects
				(font
					(size 1.27 1.27)
					(thickness 0.15)
				)
				(justify left bottom)
				(hide yes)
			)
		)
		(property "Author" "Antmicro"
			(at 210.82 85.09 0)
			(effects
				(font
					(size 1.27 1.27)
					(thickness 0.15)
				)
				(justify left bottom)
				(hide yes)
			)
		)
		(property "Val" "1u"
			(at 187.452 104.14 90)
			(effects
				(font
					(size 1.27 1.27)
					(thickness 0.15)
				)
				(justify right)
			)
		)
		(property "Voltage" "25V"
			(at 213.36 85.09 0)
			(effects
				(font
					(size 1.27 1.27)
				)
				(justify left bottom)
				(hide yes)
			)
		)
		(property "Dielectric" "X5R"
			(at 215.9 85.09 0)
			(effects
				(font
					(size 1.27 1.27)
				)
				(justify left bottom)
				(hide yes)
			)
		)
		(pin "1"
		)
		(pin "2"
		)
		(instances
			(project "OCuLink to 10GbE adapter"
				(path ""
					(reference "C58")
					(unit 1)
				)
			)
			(project "thunderbolt-to-10gbe-adapter"
				(path ""
					(reference "C298")
					(unit 1)
				)
			)
		)
	)
	(symbol
		(lib_id "antmicroCapacitors0402:C_470p_0402")
		(at 233.68 102.87 90)
		(unit 1)
		(exclude_from_sim no)
		(in_bom yes)
		(on_board yes)
		(dnp no)
		(property "Reference" "C302"
			(at 235.712 99.06 90)
			(effects
				(font
					(size 1.27 1.27)
					(thickness 0.15)
				)
				(justify right)
			)
		)
		(property "Value" "C_470p_0402"
			(at 243.84 82.55 0)
			(effects
				(font
					(size 1.27 1.27)
					(thickness 0.15)
				)
				(justify left bottom)
				(hide yes)
			)
		)
		(property "Footprint" "antmicro-footprints:C_0402_1005Metric"
			(at 246.38 82.55 0)
			(effects
				(font
					(size 1.27 1.27)
					(thickness 0.15)
				)
				(justify left bottom)
				(hide yes)
			)
		)
		(property "Datasheet" "https://www.passivecomponent.com/wp-content/uploads/datasheet/WTC_MLCC_General_Purpose.pdf"
			(at 248.92 82.55 0)
			(effects
				(font
					(size 1.27 1.27)
					(thickness 0.15)
				)
				(justify left bottom)
				(hide yes)
			)
		)
		(property "Description" "SMD Multilayer Ceramic Capacitor, General Purpose, 470 pF, 25 V, 0402 [1005 Metric], ± 10%, X7R"
			(at 233.68 102.87 0)
			(effects
				(font
					(size 1.27 1.27)
				)
				(hide yes)
			)
		)
		(property "MPN" "0402B471K250CT"
			(at 251.46 82.55 0)
			(effects
				(font
					(size 1.27 1.27)
					(thickness 0.15)
				)
				(justify left bottom)
				(hide yes)
			)
		)
		(property "Manufacturer" "Walsin"
			(at 254 82.55 0)
			(effects
				(font
					(size 1.27 1.27)
					(thickness 0.15)
				)
				(justify left bottom)
				(hide yes)
			)
		)
		(property "License" "Apache-2.0"
			(at 256.54 82.55 0)
			(effects
				(font
					(size 1.27 1.27)
					(thickness 0.15)
				)
				(justify left bottom)
				(hide yes)
			)
		)
		(property "Author" "Antmicro"
			(at 259.08 82.55 0)
			(effects
				(font
					(size 1.27 1.27)
					(thickness 0.15)
				)
				(justify left bottom)
				(hide yes)
			)
		)
		(property "Val" "470p"
			(at 235.712 101.6 90)
			(effects
				(font
					(size 1.27 1.27)
					(thickness 0.15)
				)
				(justify right)
			)
		)
		(property "Voltage" "25V"
			(at 261.62 82.55 0)
			(effects
				(font
					(size 1.27 1.27)
				)
				(justify left bottom)
				(hide yes)
			)
		)
		(property "Dielectric" "X7R"
			(at 264.16 82.55 0)
			(effects
				(font
					(size 1.27 1.27)
				)
				(justify left bottom)
				(hide yes)
			)
		)
		(pin "2"
		)
		(pin "1"
		)
		(instances
			(project ""
				(path ""
					(reference "C48")
					(unit 1)
				)
			)
			(project "thunderbolt-to-10gbe-adapter"
				(path ""
					(reference "C302")
					(unit 1)
				)
			)
		)
	)
	(symbol
		(lib_id "antmicroCapacitorsmisc:C_100u_0805")
		(at 154.94 241.3 90)
		(unit 1)
		(exclude_from_sim no)
		(in_bom yes)
		(on_board yes)
		(dnp no)
		(property "Reference" "C293"
			(at 156.972 237.49 90)
			(effects
				(font
					(size 1.27 1.27)
					(thickness 0.15)
				)
				(justify right)
			)
		)
		(property "Value" "C_100u_0805"
			(at 165.1 220.98 0)
			(effects
				(font
					(size 1.27 1.27)
					(thickness 0.15)
				)
				(justify left bottom)
				(hide yes)
			)
		)
		(property "Footprint" "antmicro-footprints:C_0805_2012Metric"
			(at 167.64 220.98 0)
			(effects
				(font
					(size 1.27 1.27)
					(thickness 0.15)
				)
				(justify left bottom)
				(hide yes)
			)
		)
		(property "Datasheet" "https://www.murata.com/products/productdetail?partno=GRM21BR60J107ME15%23"
			(at 170.18 220.98 0)
			(effects
				(font
					(size 1.27 1.27)
					(thickness 0.15)
				)
				(justify left bottom)
				(hide yes)
			)
		)
		(property "Description" "SMD Multilayer Ceramic Capacitor, 100 µF, 6.3 V, 0805 [2012 Metric], ± 20%, X5R, GRM Series"
			(at 154.94 241.3 0)
			(effects
				(font
					(size 1.27 1.27)
				)
				(hide yes)
			)
		)
		(property "MPN" "GRM21BR60J107ME15L"
			(at 172.72 220.98 0)
			(effects
				(font
					(size 1.27 1.27)
					(thickness 0.15)
				)
				(justify left bottom)
				(hide yes)
			)
		)
		(property "Manufacturer" "Murata"
			(at 175.26 220.98 0)
			(effects
				(font
					(size 1.27 1.27)
					(thickness 0.15)
				)
				(justify left bottom)
				(hide yes)
			)
		)
		(property "License" "Apache-2.0"
			(at 177.8 220.98 0)
			(effects
				(font
					(size 1.27 1.27)
					(thickness 0.15)
				)
				(justify left bottom)
				(hide yes)
			)
		)
		(property "Author" "Antmicro"
			(at 180.34 220.98 0)
			(effects
				(font
					(size 1.27 1.27)
					(thickness 0.15)
				)
				(justify left bottom)
				(hide yes)
			)
		)
		(property "Val" "100u"
			(at 156.972 240.03 90)
			(effects
				(font
					(size 1.27 1.27)
					(thickness 0.15)
				)
				(justify right)
			)
		)
		(property "Voltage" ""
			(at 182.88 220.98 0)
			(effects
				(font
					(size 1.27 1.27)
				)
				(justify left bottom)
				(hide yes)
			)
		)
		(property "Dielectric" ""
			(at 185.42 220.98 0)
			(effects
				(font
					(size 1.27 1.27)
				)
				(justify left bottom)
				(hide yes)
			)
		)
		(property "Public" "False"
			(at 187.96 220.98 0)
			(effects
				(font
					(size 1.27 1.27)
				)
				(justify left bottom)
				(hide yes)
			)
		)
		(pin "1"
		)
		(pin "2"
		)
		(instances
			(project "OCuLink to 10GbE adapter"
				(path ""
					(reference "C63")
					(unit 1)
				)
			)
			(project "thunderbolt-to-10gbe-adapter"
				(path ""
					(reference "C293")
					(unit 1)
				)
			)
		)
	)
	(symbol
		(lib_id "antmicroResistors0402:R_220R_0402")
		(at 259.08 220.98 0)
		(unit 1)
		(exclude_from_sim no)
		(in_bom yes)
		(on_board yes)
		(dnp no)
		(property "Reference" "R214"
			(at 259.08 219.71 0)
			(effects
				(font
					(size 1.27 1.27)
					(thickness 0.15)
				)
				(justify right)
			)
		)
		(property "Value" "R_220R_0402"
			(at 279.4 233.68 0)
			(effects
				(font
					(size 1.27 1.27)
					(thickness 0.15)
				)
				(justify left bottom)
				(hide yes)
			)
		)
		(property "Footprint" "antmicro-footprints:R_0402_1005Metric"
			(at 279.4 236.22 0)
			(effects
				(font
					(size 1.27 1.27)
					(thickness 0.15)
				)
				(justify left bottom)
				(hide yes)
			)
		)
		(property "Datasheet" "https://www.bourns.com/docs/product-datasheets/cr.pdf"
			(at 279.4 238.76 0)
			(effects
				(font
					(size 1.27 1.27)
					(thickness 0.15)
				)
				(justify left bottom)
				(hide yes)
			)
		)
		(property "Description" "SMD Chip Resistor, 220 ohm, ± 1%, 62.5 mW, 0402 [1005 Metric], Thick Film, General Purpose"
			(at 259.08 220.98 0)
			(effects
				(font
					(size 1.27 1.27)
				)
				(hide yes)
			)
		)
		(property "MPN" "CR0402-FX-2200GLF"
			(at 279.4 241.3 0)
			(effects
				(font
					(size 1.27 1.27)
					(thickness 0.15)
				)
				(justify left bottom)
				(hide yes)
			)
		)
		(property "Manufacturer" "Bourns"
			(at 279.4 243.84 0)
			(effects
				(font
					(size 1.27 1.27)
					(thickness 0.15)
				)
				(justify left bottom)
				(hide yes)
			)
		)
		(property "License" "Apache-2.0"
			(at 279.4 246.38 0)
			(effects
				(font
					(size 1.27 1.27)
					(thickness 0.15)
				)
				(justify left bottom)
				(hide yes)
			)
		)
		(property "Author" "Antmicro"
			(at 279.4 248.92 0)
			(effects
				(font
					(size 1.27 1.27)
					(thickness 0.15)
				)
				(justify left bottom)
				(hide yes)
			)
		)
		(property "Val" "220R"
			(at 264.16 219.71 0)
			(effects
				(font
					(size 1.27 1.27)
					(thickness 0.15)
				)
				(justify left)
			)
		)
		(property "Tolerance" "1%"
			(at 279.4 231.14 0)
			(effects
				(font
					(size 1.27 1.27)
				)
				(justify left bottom)
				(hide yes)
			)
		)
		(pin "1"
		)
		(pin "2"
		)
		(instances
			(project "OCuLink to 10GbE adapter"
				(path ""
					(reference "R40")
					(unit 1)
				)
			)
			(project "thunderbolt-to-10gbe-adapter"
				(path ""
					(reference "R214")
					(unit 1)
				)
			)
		)
	)
	(symbol
		(lib_id "antmicroCapacitors0402:C_470p_0402")
		(at 243.84 238.76 90)
		(unit 1)
		(exclude_from_sim no)
		(in_bom yes)
		(on_board yes)
		(dnp no)
		(property "Reference" "C305"
			(at 245.872 234.95 90)
			(effects
				(font
					(size 1.27 1.27)
					(thickness 0.15)
				)
				(justify right)
			)
		)
		(property "Value" "C_470p_0402"
			(at 254 218.44 0)
			(effects
				(font
					(size 1.27 1.27)
					(thickness 0.15)
				)
				(justify left bottom)
				(hide yes)
			)
		)
		(property "Footprint" "antmicro-footprints:C_0402_1005Metric"
			(at 256.54 218.44 0)
			(effects
				(font
					(size 1.27 1.27)
					(thickness 0.15)
				)
				(justify left bottom)
				(hide yes)
			)
		)
		(property "Datasheet" "https://www.passivecomponent.com/wp-content/uploads/datasheet/WTC_MLCC_General_Purpose.pdf"
			(at 259.08 218.44 0)
			(effects
				(font
					(size 1.27 1.27)
					(thickness 0.15)
				)
				(justify left bottom)
				(hide yes)
			)
		)
		(property "Description" "SMD Multilayer Ceramic Capacitor, General Purpose, 470 pF, 25 V, 0402 [1005 Metric], ± 10%, X7R"
			(at 243.84 238.76 0)
			(effects
				(font
					(size 1.27 1.27)
				)
				(hide yes)
			)
		)
		(property "MPN" "0402B471K250CT"
			(at 261.62 218.44 0)
			(effects
				(font
					(size 1.27 1.27)
					(thickness 0.15)
				)
				(justify left bottom)
				(hide yes)
			)
		)
		(property "Manufacturer" "Walsin"
			(at 264.16 218.44 0)
			(effects
				(font
					(size 1.27 1.27)
					(thickness 0.15)
				)
				(justify left bottom)
				(hide yes)
			)
		)
		(property "License" "Apache-2.0"
			(at 266.7 218.44 0)
			(effects
				(font
					(size 1.27 1.27)
					(thickness 0.15)
				)
				(justify left bottom)
				(hide yes)
			)
		)
		(property "Author" "Antmicro"
			(at 269.24 218.44 0)
			(effects
				(font
					(size 1.27 1.27)
					(thickness 0.15)
				)
				(justify left bottom)
				(hide yes)
			)
		)
		(property "Val" "470p"
			(at 245.872 237.49 90)
			(effects
				(font
					(size 1.27 1.27)
					(thickness 0.15)
				)
				(justify right)
			)
		)
		(property "Voltage" "25V"
			(at 271.78 218.44 0)
			(effects
				(font
					(size 1.27 1.27)
				)
				(justify left bottom)
				(hide yes)
			)
		)
		(property "Dielectric" "X7R"
			(at 274.32 218.44 0)
			(effects
				(font
					(size 1.27 1.27)
				)
				(justify left bottom)
				(hide yes)
			)
		)
		(pin "2"
		)
		(pin "1"
		)
		(instances
			(project "OCuLink to 10GbE adapter"
				(path ""
					(reference "C61")
					(unit 1)
				)
			)
			(project "thunderbolt-to-10gbe-adapter"
				(path ""
					(reference "C305")
					(unit 1)
				)
			)
		)
	)
	(symbol
		(lib_id "antmicropower:GND")
		(at 167.64 107.95 0)
		(unit 1)
		(exclude_from_sim no)
		(in_bom yes)
		(on_board yes)
		(dnp no)
		(property "Reference" "#PWR0439"
			(at 176.53 110.49 0)
			(effects
				(font
					(size 1.27 1.27)
					(thickness 0.15)
				)
				(justify left bottom)
				(hide yes)
			)
		)
		(property "Value" "GND"
			(at 167.64 111.76 0)
			(effects
				(font
					(size 1.27 1.27)
					(thickness 0.15)
				)
			)
		)
		(property "Footprint" ""
			(at 176.53 115.57 0)
			(effects
				(font
					(size 1.27 1.27)
					(thickness 0.15)
				)
				(justify left bottom)
				(hide yes)
			)
		)
		(property "Datasheet" ""
			(at 176.53 120.65 0)
			(effects
				(font
					(size 1.27 1.27)
					(thickness 0.15)
				)
				(justify left bottom)
				(hide yes)
			)
		)
		(property "Description" ""
			(at 167.64 107.95 0)
			(effects
				(font
					(size 1.27 1.27)
				)
				(hide yes)
			)
		)
		(property "Author" "Antmicro"
			(at 176.53 115.57 0)
			(effects
				(font
					(size 1.27 1.27)
					(thickness 0.15)
				)
				(justify left bottom)
				(hide yes)
			)
		)
		(property "License" "Apache-2.0"
			(at 176.53 118.11 0)
			(effects
				(font
					(size 1.27 1.27)
					(thickness 0.15)
				)
				(justify left bottom)
				(hide yes)
			)
		)
		(pin "1"
		)
		(instances
			(project "OCuLink to 10GbE adapter"
				(path ""
					(reference "#PWR075")
					(unit 1)
				)
			)
			(project "thunderbolt-to-10gbe-adapter"
				(path ""
					(reference "#PWR0439")
					(unit 1)
				)
			)
		)
	)
	(symbol
		(lib_id "antmicroModularConnectorsJacksWithMagnetics:Bus_RJ45_JTH-0024NL")
		(at 204.47 198.12 0)
		(unit 1)
		(exclude_from_sim no)
		(in_bom yes)
		(on_board yes)
		(dnp no)
		(fields_autoplaced yes)
		(property "Reference" "J4"
			(at 215.265 190.5 0)
			(effects
				(font
					(size 1.27 1.27)
					(thickness 0.15)
				)
			)
		)
		(property "Value" "Bus_RJ45_JTH-0024NL"
			(at 240.03 203.2 0)
			(effects
				(font
					(size 1.27 1.27)
					(thickness 0.15)
				)
				(justify left bottom)
				(hide yes)
			)
		)
		(property "Footprint" "antmicro-footprints:RJ45_JTH-0024NL"
			(at 240.03 205.74 0)
			(effects
				(font
					(size 1.27 1.27)
					(thickness 0.15)
				)
				(justify left bottom)
				(hide yes)
			)
		)
		(property "Datasheet" "https://www.mouser.com/datasheet/2/447/JTH_0024NL-3072047.pdf"
			(at 240.03 208.28 0)
			(effects
				(font
					(size 1.27 1.27)
					(thickness 0.15)
				)
				(justify left bottom)
				(hide yes)
			)
		)
		(property "Description" "Modular Connectors / Ethernet Connectors 1X1 TAB DOWN W/LED'S ETHERNET (NON PoE)"
			(at 204.47 198.12 0)
			(effects
				(font
					(size 1.27 1.27)
				)
				(hide yes)
			)
		)
		(property "MPN" "JTH-0024NL"
			(at 215.265 193.04 0)
			(effects
				(font
					(size 1.27 1.27)
					(thickness 0.15)
				)
			)
		)
		(property "Manufacturer" "Pulse Electronics"
			(at 240.03 213.36 0)
			(effects
				(font
					(size 1.27 1.27)
					(thickness 0.15)
				)
				(justify left bottom)
				(hide yes)
			)
		)
		(property "Author" "Antmicro"
			(at 240.03 215.9 0)
			(effects
				(font
					(size 1.27 1.27)
					(thickness 0.15)
				)
				(justify left bottom)
				(hide yes)
			)
		)
		(property "License" "Apache-2.0"
			(at 240.03 218.44 0)
			(effects
				(font
					(size 1.27 1.27)
					(thickness 0.15)
				)
				(justify left bottom)
				(hide yes)
			)
		)
		(pin "8"
		)
		(pin "14"
		)
		(pin "9"
		)
		(pin "11"
		)
		(pin "10"
		)
		(pin "SH"
		)
		(pin "13"
		)
		(pin "17"
		)
		(pin "6"
		)
		(pin "12"
		)
		(pin "1"
		)
		(pin "2"
		)
		(pin "4"
		)
		(pin "5"
		)
		(pin "3"
		)
		(pin "7"
		)
		(pin "15"
		)
		(pin "16"
		)
		(instances
			(project "OCuLink to 10GbE adapter"
				(path ""
					(reference "J6")
					(unit 1)
				)
			)
			(project "thunderbolt-to-10gbe-adapter"
				(path ""
					(reference "J4")
					(unit 1)
				)
			)
		)
	)
	(symbol
		(lib_id "antmicroFixedInductors:L_2n4_0.85A_0402")
		(at 147.32 233.68 0)
		(unit 1)
		(exclude_from_sim no)
		(in_bom yes)
		(on_board yes)
		(dnp no)
		(property "Reference" "L13"
			(at 149.86 229.108 0)
			(effects
				(font
					(size 1.27 1.27)
					(thickness 0.15)
				)
			)
		)
		(property "Value" "L_2n4_0.85A_0402"
			(at 161.29 236.22 0)
			(effects
				(font
					(size 1.27 1.27)
					(thickness 0.15)
				)
				(justify left bottom)
				(hide yes)
			)
		)
		(property "Footprint" "antmicro-footprints:L_0402_1005Metric"
			(at 161.29 241.3 0)
			(effects
				(font
					(size 1.27 1.27)
					(thickness 0.15)
				)
				(justify left bottom)
				(hide yes)
			)
		)
		(property "Datasheet" "https://www.murata.com/products/productdetail?partno=LQW15AN2N4B00%23"
			(at 161.29 243.84 0)
			(effects
				(font
					(size 1.27 1.27)
					(thickness 0.15)
				)
				(justify left bottom)
				(hide yes)
			)
		)
		(property "Description" "Wirewound Inductor, 2.4 nH, 0.05 ohm, 15 GHz, 850 mA, 0402 [1005 Metric], LQW15AN"
			(at 147.32 233.68 0)
			(effects
				(font
					(size 1.27 1.27)
				)
				(hide yes)
			)
		)
		(property "Val" "2n4/0.85A"
			(at 149.86 231.648 0)
			(effects
				(font
					(size 1.27 1.27)
					(thickness 0.15)
				)
			)
		)
		(property "Manufacturer" "Murata"
			(at 161.29 246.38 0)
			(effects
				(font
					(size 1.27 1.27)
					(thickness 0.15)
				)
				(justify left bottom)
				(hide yes)
			)
		)
		(property "MPN" "LQW15AN2N4B00D"
			(at 161.29 248.92 0)
			(effects
				(font
					(size 1.27 1.27)
					(thickness 0.15)
				)
				(justify left bottom)
				(hide yes)
			)
		)
		(property "ISat" "0.85 A"
			(at 161.29 250.19 0)
			(effects
				(font
					(size 1.27 1.27)
				)
				(justify left)
				(hide yes)
			)
		)
		(property "IMax" "0.85 A"
			(at 161.29 254 0)
			(effects
				(font
					(size 1.27 1.27)
					(thickness 0.15)
				)
				(justify left bottom)
				(hide yes)
			)
		)
		(property "Size" "1.0x0.5"
			(at 161.29 256.54 0)
			(effects
				(font
					(size 1.27 1.27)
					(thickness 0.15)
				)
				(justify left bottom)
				(hide yes)
			)
		)
		(property "Author" "Antmicro"
			(at 161.29 259.08 0)
			(effects
				(font
					(size 1.27 1.27)
					(thickness 0.15)
				)
				(justify left bottom)
				(hide yes)
			)
		)
		(property "License" "Apache-2.0"
			(at 161.29 261.62 0)
			(effects
				(font
					(size 1.27 1.27)
					(thickness 0.15)
				)
				(justify left bottom)
				(hide yes)
			)
		)
		(pin "2"
		)
		(pin "1"
		)
		(instances
			(project "OCuLink to 10GbE adapter"
				(path ""
					(reference "L7")
					(unit 1)
				)
			)
			(project "thunderbolt-to-10gbe-adapter"
				(path ""
					(reference "L13")
					(unit 1)
				)
			)
		)
	)
	(symbol
		(lib_id "antmicropower:GND")
		(at 86.36 107.95 0)
		(unit 1)
		(exclude_from_sim no)
		(in_bom yes)
		(on_board yes)
		(dnp no)
		(property "Reference" "#PWR0432"
			(at 95.25 110.49 0)
			(effects
				(font
					(size 1.27 1.27)
					(thickness 0.15)
				)
				(justify left bottom)
				(hide yes)
			)
		)
		(property "Value" "GND"
			(at 86.36 111.76 0)
			(effects
				(font
					(size 1.27 1.27)
					(thickness 0.15)
				)
			)
		)
		(property "Footprint" ""
			(at 95.25 115.57 0)
			(effects
				(font
					(size 1.27 1.27)
					(thickness 0.15)
				)
				(justify left bottom)
				(hide yes)
			)
		)
		(property "Datasheet" ""
			(at 95.25 120.65 0)
			(effects
				(font
					(size 1.27 1.27)
					(thickness 0.15)
				)
				(justify left bottom)
				(hide yes)
			)
		)
		(property "Description" ""
			(at 86.36 107.95 0)
			(effects
				(font
					(size 1.27 1.27)
				)
				(hide yes)
			)
		)
		(property "Author" "Antmicro"
			(at 95.25 115.57 0)
			(effects
				(font
					(size 1.27 1.27)
					(thickness 0.15)
				)
				(justify left bottom)
				(hide yes)
			)
		)
		(property "License" "Apache-2.0"
			(at 95.25 118.11 0)
			(effects
				(font
					(size 1.27 1.27)
					(thickness 0.15)
				)
				(justify left bottom)
				(hide yes)
			)
		)
		(pin "1"
		)
		(instances
			(project "OCuLink to 10GbE adapter"
				(path ""
					(reference "#PWR072")
					(unit 1)
				)
			)
			(project "thunderbolt-to-10gbe-adapter"
				(path ""
					(reference "#PWR0432")
					(unit 1)
				)
			)
		)
	)
	(symbol
		(lib_id "antmicroCapacitors0402:C_470p_0402")
		(at 243.84 102.87 90)
		(unit 1)
		(exclude_from_sim no)
		(in_bom yes)
		(on_board yes)
		(dnp no)
		(property "Reference" "C304"
			(at 245.872 99.06 90)
			(effects
				(font
					(size 1.27 1.27)
					(thickness 0.15)
				)
				(justify right)
			)
		)
		(property "Value" "C_470p_0402"
			(at 254 82.55 0)
			(effects
				(font
					(size 1.27 1.27)
					(thickness 0.15)
				)
				(justify left bottom)
				(hide yes)
			)
		)
		(property "Footprint" "antmicro-footprints:C_0402_1005Metric"
			(at 256.54 82.55 0)
			(effects
				(font
					(size 1.27 1.27)
					(thickness 0.15)
				)
				(justify left bottom)
				(hide yes)
			)
		)
		(property "Datasheet" "https://www.passivecomponent.com/wp-content/uploads/datasheet/WTC_MLCC_General_Purpose.pdf"
			(at 259.08 82.55 0)
			(effects
				(font
					(size 1.27 1.27)
					(thickness 0.15)
				)
				(justify left bottom)
				(hide yes)
			)
		)
		(property "Description" "SMD Multilayer Ceramic Capacitor, General Purpose, 470 pF, 25 V, 0402 [1005 Metric], ± 10%, X7R"
			(at 243.84 102.87 0)
			(effects
				(font
					(size 1.27 1.27)
				)
				(hide yes)
			)
		)
		(property "MPN" "0402B471K250CT"
			(at 261.62 82.55 0)
			(effects
				(font
					(size 1.27 1.27)
					(thickness 0.15)
				)
				(justify left bottom)
				(hide yes)
			)
		)
		(property "Manufacturer" "Walsin"
			(at 264.16 82.55 0)
			(effects
				(font
					(size 1.27 1.27)
					(thickness 0.15)
				)
				(justify left bottom)
				(hide yes)
			)
		)
		(property "License" "Apache-2.0"
			(at 266.7 82.55 0)
			(effects
				(font
					(size 1.27 1.27)
					(thickness 0.15)
				)
				(justify left bottom)
				(hide yes)
			)
		)
		(property "Author" "Antmicro"
			(at 269.24 82.55 0)
			(effects
				(font
					(size 1.27 1.27)
					(thickness 0.15)
				)
				(justify left bottom)
				(hide yes)
			)
		)
		(property "Val" "470p"
			(at 245.872 101.6 90)
			(effects
				(font
					(size 1.27 1.27)
					(thickness 0.15)
				)
				(justify right)
			)
		)
		(property "Voltage" "25V"
			(at 271.78 82.55 0)
			(effects
				(font
					(size 1.27 1.27)
				)
				(justify left bottom)
				(hide yes)
			)
		)
		(property "Dielectric" "X7R"
			(at 274.32 82.55 0)
			(effects
				(font
					(size 1.27 1.27)
				)
				(justify left bottom)
				(hide yes)
			)
		)
		(pin "2"
		)
		(pin "1"
		)
		(instances
			(project "OCuLink to 10GbE adapter"
				(path ""
					(reference "C49")
					(unit 1)
				)
			)
			(project "thunderbolt-to-10gbe-adapter"
				(path ""
					(reference "C304")
					(unit 1)
				)
			)
		)
	)
	(symbol
		(lib_id "antmicropower:+1V8")
		(at 59.69 95.25 0)
		(unit 1)
		(exclude_from_sim no)
		(in_bom yes)
		(on_board yes)
		(dnp no)
		(property "Reference" "#PWR0429"
			(at 74.93 97.79 0)
			(effects
				(font
					(size 1.27 1.27)
					(thickness 0.15)
				)
				(justify left bottom)
				(hide yes)
			)
		)
		(property "Value" "+1V88"
			(at 59.69 91.44 0)
			(effects
				(font
					(size 1.27 1.27)
					(thickness 0.15)
				)
			)
		)
		(property "Footprint" ""
			(at 74.93 102.87 0)
			(effects
				(font
					(size 1.27 1.27)
					(thickness 0.15)
				)
				(justify left bottom)
				(hide yes)
			)
		)
		(property "Datasheet" ""
			(at 74.93 105.41 0)
			(effects
				(font
					(size 1.27 1.27)
					(thickness 0.15)
				)
				(justify left bottom)
				(hide yes)
			)
		)
		(property "Description" ""
			(at 59.69 95.25 0)
			(effects
				(font
					(size 1.27 1.27)
				)
				(hide yes)
			)
		)
		(property "Author" "Antmicro"
			(at 74.93 100.33 0)
			(effects
				(font
					(size 1.27 1.27)
					(thickness 0.15)
				)
				(justify left bottom)
				(hide yes)
			)
		)
		(property "License" "Apache-2.0"
			(at 74.93 102.87 0)
			(effects
				(font
					(size 1.27 1.27)
					(thickness 0.15)
				)
				(justify left bottom)
				(hide yes)
			)
		)
		(pin "1"
		)
		(instances
			(project "OCuLink to 10GbE adapter"
				(path ""
					(reference "#PWR067")
					(unit 1)
				)
			)
			(project "thunderbolt-to-10gbe-adapter"
				(path ""
					(reference "#PWR0429")
					(unit 1)
				)
			)
		)
	)
	(symbol
		(lib_id "antmicropower:GND")
		(at 194.31 243.84 0)
		(unit 1)
		(exclude_from_sim no)
		(in_bom yes)
		(on_board yes)
		(dnp no)
		(property "Reference" "#PWR0446"
			(at 203.2 246.38 0)
			(effects
				(font
					(size 1.27 1.27)
					(thickness 0.15)
				)
				(justify left bottom)
				(hide yes)
			)
		)
		(property "Value" "GND"
			(at 194.31 247.65 0)
			(effects
				(font
					(size 1.27 1.27)
					(thickness 0.15)
				)
			)
		)
		(property "Footprint" ""
			(at 203.2 251.46 0)
			(effects
				(font
					(size 1.27 1.27)
					(thickness 0.15)
				)
				(justify left bottom)
				(hide yes)
			)
		)
		(property "Datasheet" ""
			(at 203.2 256.54 0)
			(effects
				(font
					(size 1.27 1.27)
					(thickness 0.15)
				)
				(justify left bottom)
				(hide yes)
			)
		)
		(property "Description" ""
			(at 194.31 243.84 0)
			(effects
				(font
					(size 1.27 1.27)
				)
				(hide yes)
			)
		)
		(property "Author" "Antmicro"
			(at 203.2 251.46 0)
			(effects
				(font
					(size 1.27 1.27)
					(thickness 0.15)
				)
				(justify left bottom)
				(hide yes)
			)
		)
		(property "License" "Apache-2.0"
			(at 203.2 254 0)
			(effects
				(font
					(size 1.27 1.27)
					(thickness 0.15)
				)
				(justify left bottom)
				(hide yes)
			)
		)
		(pin "1"
		)
		(instances
			(project "OCuLink to 10GbE adapter"
				(path ""
					(reference "#PWR087")
					(unit 1)
				)
			)
			(project "thunderbolt-to-10gbe-adapter"
				(path ""
					(reference "#PWR0446")
					(unit 1)
				)
			)
		)
	)
	(symbol
		(lib_id "antmicroCapacitors0402:C_1u_25V_0402")
		(at 185.42 241.3 90)
		(unit 1)
		(exclude_from_sim no)
		(in_bom yes)
		(on_board yes)
		(dnp no)
		(property "Reference" "C299"
			(at 187.452 237.49 90)
			(effects
				(font
					(size 1.27 1.27)
					(thickness 0.15)
				)
				(justify right)
			)
		)
		(property "Value" "C_1u_25V_0402"
			(at 195.58 220.98 0)
			(effects
				(font
					(size 1.27 1.27)
					(thickness 0.15)
				)
				(justify left bottom)
				(hide yes)
			)
		)
		(property "Footprint" "antmicro-footprints:C_0402_1005Metric"
			(at 198.12 220.98 0)
			(effects
				(font
					(size 1.27 1.27)
					(thickness 0.15)
				)
				(justify left bottom)
				(hide yes)
			)
		)
		(property "Datasheet" "https://www.murata.com/products/productdetail?partno=GRM155R61E105KE11%23"
			(at 200.66 220.98 0)
			(effects
				(font
					(size 1.27 1.27)
					(thickness 0.15)
				)
				(justify left bottom)
				(hide yes)
			)
		)
		(property "Description" "SMD Multilayer Ceramic Capacitor, 1 µF, 25 V, 0402 [1005 Metric], ± 10%, X5R, GRM Series"
			(at 185.42 241.3 0)
			(effects
				(font
					(size 1.27 1.27)
				)
				(hide yes)
			)
		)
		(property "MPN" "GRM155R61E105KE11J"
			(at 203.2 220.98 0)
			(effects
				(font
					(size 1.27 1.27)
					(thickness 0.15)
				)
				(justify left bottom)
				(hide yes)
			)
		)
		(property "Manufacturer" "Murata"
			(at 205.74 220.98 0)
			(effects
				(font
					(size 1.27 1.27)
					(thickness 0.15)
				)
				(justify left bottom)
				(hide yes)
			)
		)
		(property "License" "Apache-2.0"
			(at 208.28 220.98 0)
			(effects
				(font
					(size 1.27 1.27)
					(thickness 0.15)
				)
				(justify left bottom)
				(hide yes)
			)
		)
		(property "Author" "Antmicro"
			(at 210.82 220.98 0)
			(effects
				(font
					(size 1.27 1.27)
					(thickness 0.15)
				)
				(justify left bottom)
				(hide yes)
			)
		)
		(property "Val" "1u"
			(at 187.452 240.03 90)
			(effects
				(font
					(size 1.27 1.27)
					(thickness 0.15)
				)
				(justify right)
			)
		)
		(property "Voltage" "25V"
			(at 213.36 220.98 0)
			(effects
				(font
					(size 1.27 1.27)
				)
				(justify left bottom)
				(hide yes)
			)
		)
		(property "Dielectric" "X5R"
			(at 215.9 220.98 0)
			(effects
				(font
					(size 1.27 1.27)
				)
				(justify left bottom)
				(hide yes)
			)
		)
		(pin "1"
		)
		(pin "2"
		)
		(instances
			(project "OCuLink to 10GbE adapter"
				(path ""
					(reference "C66")
					(unit 1)
				)
			)
			(project "thunderbolt-to-10gbe-adapter"
				(path ""
					(reference "C299")
					(unit 1)
				)
			)
		)
	)
	(symbol
		(lib_id "antmicroCapacitorsmisc:C_100u_0805")
		(at 154.94 105.41 90)
		(unit 1)
		(exclude_from_sim no)
		(in_bom yes)
		(on_board yes)
		(dnp no)
		(property "Reference" "C292"
			(at 156.972 101.6 90)
			(effects
				(font
					(size 1.27 1.27)
					(thickness 0.15)
				)
				(justify right)
			)
		)
		(property "Value" "C_100u_0805"
			(at 165.1 85.09 0)
			(effects
				(font
					(size 1.27 1.27)
					(thickness 0.15)
				)
				(justify left bottom)
				(hide yes)
			)
		)
		(property "Footprint" "antmicro-footprints:C_0805_2012Metric"
			(at 167.64 85.09 0)
			(effects
				(font
					(size 1.27 1.27)
					(thickness 0.15)
				)
				(justify left bottom)
				(hide yes)
			)
		)
		(property "Datasheet" "https://www.murata.com/products/productdetail?partno=GRM21BR60J107ME15%23"
			(at 170.18 85.09 0)
			(effects
				(font
					(size 1.27 1.27)
					(thickness 0.15)
				)
				(justify left bottom)
				(hide yes)
			)
		)
		(property "Description" "SMD Multilayer Ceramic Capacitor, 100 µF, 6.3 V, 0805 [2012 Metric], ± 20%, X5R, GRM Series"
			(at 154.94 105.41 0)
			(effects
				(font
					(size 1.27 1.27)
				)
				(hide yes)
			)
		)
		(property "MPN" "GRM21BR60J107ME15L"
			(at 172.72 85.09 0)
			(effects
				(font
					(size 1.27 1.27)
					(thickness 0.15)
				)
				(justify left bottom)
				(hide yes)
			)
		)
		(property "Manufacturer" "Murata"
			(at 175.26 85.09 0)
			(effects
				(font
					(size 1.27 1.27)
					(thickness 0.15)
				)
				(justify left bottom)
				(hide yes)
			)
		)
		(property "License" "Apache-2.0"
			(at 177.8 85.09 0)
			(effects
				(font
					(size 1.27 1.27)
					(thickness 0.15)
				)
				(justify left bottom)
				(hide yes)
			)
		)
		(property "Author" "Antmicro"
			(at 180.34 85.09 0)
			(effects
				(font
					(size 1.27 1.27)
					(thickness 0.15)
				)
				(justify left bottom)
				(hide yes)
			)
		)
		(property "Val" "100u"
			(at 156.972 104.14 90)
			(effects
				(font
					(size 1.27 1.27)
					(thickness 0.15)
				)
				(justify right)
			)
		)
		(property "Voltage" ""
			(at 182.88 85.09 0)
			(effects
				(font
					(size 1.27 1.27)
				)
				(justify left bottom)
				(hide yes)
			)
		)
		(property "Dielectric" ""
			(at 185.42 85.09 0)
			(effects
				(font
					(size 1.27 1.27)
				)
				(justify left bottom)
				(hide yes)
			)
		)
		(property "Public" "False"
			(at 187.96 85.09 0)
			(effects
				(font
					(size 1.27 1.27)
				)
				(justify left bottom)
				(hide yes)
			)
		)
		(pin "1"
		)
		(pin "2"
		)
		(instances
			(project ""
				(path ""
					(reference "C55")
					(unit 1)
				)
			)
			(project "thunderbolt-to-10gbe-adapter"
				(path ""
					(reference "C292")
					(unit 1)
				)
			)
		)
	)
	(symbol
		(lib_id "antmicropower:PWR_FLAG")
		(at 106.68 96.52 0)
		(unit 1)
		(exclude_from_sim no)
		(in_bom yes)
		(on_board yes)
		(dnp no)
		(fields_autoplaced yes)
		(property "Reference" "#FLG033"
			(at 106.68 94.615 0)
			(effects
				(font
					(size 1.27 1.27)
				)
				(hide yes)
			)
		)
		(property "Value" "PWR_FLAG"
			(at 106.68 91.44 0)
			(effects
				(font
					(size 1.27 1.27)
				)
			)
		)
		(property "Footprint" ""
			(at 106.68 96.52 0)
			(effects
				(font
					(size 1.27 1.27)
				)
				(hide yes)
			)
		)
		(property "Datasheet" ""
			(at 106.68 96.52 0)
			(effects
				(font
					(size 1.27 1.27)
				)
				(hide yes)
			)
		)
		(property "Description" ""
			(at 106.68 99.06 0)
			(effects
				(font
					(size 1.27 1.27)
				)
				(justify left bottom)
				(hide yes)
			)
		)
		(pin "1"
		)
		(instances
			(project ""
				(path ""
					(reference "#FLG010")
					(unit 1)
				)
			)
			(project "thunderbolt-to-10gbe-adapter"
				(path ""
					(reference "#FLG033")
					(unit 1)
				)
			)
		)
	)
	(symbol
		(lib_id "antmicroCapacitorsmisc:C_220u_1206_6V3")
		(at 95.25 105.41 90)
		(unit 1)
		(exclude_from_sim no)
		(in_bom yes)
		(on_board yes)
		(dnp no)
		(property "Reference" "C291"
			(at 97.282 101.6 90)
			(effects
				(font
					(size 1.27 1.27)
					(thickness 0.15)
				)
				(justify right)
			)
		)
		(property "Value" "C_220u_1206_6V3"
			(at 105.41 85.09 0)
			(effects
				(font
					(size 1.27 1.27)
					(thickness 0.15)
				)
				(justify left bottom)
				(hide yes)
			)
		)
		(property "Footprint" "antmicro-footprints:C_1206_3216Metric"
			(at 107.95 85.09 0)
			(effects
				(font
					(size 1.27 1.27)
					(thickness 0.15)
				)
				(justify left bottom)
				(hide yes)
			)
		)
		(property "Datasheet" "https://www.murata.com/products/productdetail?partno=GRM31CR60J227ME11%23"
			(at 110.49 85.09 0)
			(effects
				(font
					(size 1.27 1.27)
					(thickness 0.15)
				)
				(justify left bottom)
				(hide yes)
			)
		)
		(property "Description" "SMD Multilayer Ceramic Capacitor, 220 µF, 6.3 V, 1206 [3216 Metric], ± 20%, X5R, GRM Series"
			(at 95.25 105.41 0)
			(effects
				(font
					(size 1.27 1.27)
				)
				(hide yes)
			)
		)
		(property "MPN" "GRM31CR60J227ME11L"
			(at 113.03 85.09 0)
			(effects
				(font
					(size 1.27 1.27)
					(thickness 0.15)
				)
				(justify left bottom)
				(hide yes)
			)
		)
		(property "Manufacturer" "Murata"
			(at 115.57 85.09 0)
			(effects
				(font
					(size 1.27 1.27)
					(thickness 0.15)
				)
				(justify left bottom)
				(hide yes)
			)
		)
		(property "License" "Apache-2.0"
			(at 118.11 85.09 0)
			(effects
				(font
					(size 1.27 1.27)
					(thickness 0.15)
				)
				(justify left bottom)
				(hide yes)
			)
		)
		(property "Author" "Antmicro"
			(at 120.65 85.09 0)
			(effects
				(font
					(size 1.27 1.27)
					(thickness 0.15)
				)
				(justify left bottom)
				(hide yes)
			)
		)
		(property "Val" "220u"
			(at 97.282 104.14 90)
			(effects
				(font
					(size 1.27 1.27)
					(thickness 0.15)
				)
				(justify right)
			)
		)
		(property "Voltage" ""
			(at 123.19 85.09 0)
			(effects
				(font
					(size 1.27 1.27)
				)
				(justify left bottom)
				(hide yes)
			)
		)
		(property "Dielectric" ""
			(at 125.73 85.09 0)
			(effects
				(font
					(size 1.27 1.27)
				)
				(justify left bottom)
				(hide yes)
			)
		)
		(property "Public" "False"
			(at 128.27 85.09 0)
			(effects
				(font
					(size 1.27 1.27)
				)
				(justify left bottom)
				(hide yes)
			)
		)
		(pin "1"
		)
		(pin "2"
		)
		(instances
			(project ""
				(path ""
					(reference "C54")
					(unit 1)
				)
			)
			(project "thunderbolt-to-10gbe-adapter"
				(path ""
					(reference "C291")
					(unit 1)
				)
			)
		)
	)
	(symbol
		(lib_id "antmicroResistors0402:R_220R_0402")
		(at 259.08 82.55 0)
		(unit 1)
		(exclude_from_sim no)
		(in_bom yes)
		(on_board yes)
		(dnp no)
		(property "Reference" "R210"
			(at 259.08 81.28 0)
			(effects
				(font
					(size 1.27 1.27)
					(thickness 0.15)
				)
				(justify right)
			)
		)
		(property "Value" "R_220R_0402"
			(at 279.4 95.25 0)
			(effects
				(font
					(size 1.27 1.27)
					(thickness 0.15)
				)
				(justify left bottom)
				(hide yes)
			)
		)
		(property "Footprint" "antmicro-footprints:R_0402_1005Metric"
			(at 279.4 97.79 0)
			(effects
				(font
					(size 1.27 1.27)
					(thickness 0.15)
				)
				(justify left bottom)
				(hide yes)
			)
		)
		(property "Datasheet" "https://www.bourns.com/docs/product-datasheets/cr.pdf"
			(at 279.4 100.33 0)
			(effects
				(font
					(size 1.27 1.27)
					(thickness 0.15)
				)
				(justify left bottom)
				(hide yes)
			)
		)
		(property "Description" "SMD Chip Resistor, 220 ohm, ± 1%, 62.5 mW, 0402 [1005 Metric], Thick Film, General Purpose"
			(at 259.08 82.55 0)
			(effects
				(font
					(size 1.27 1.27)
				)
				(hide yes)
			)
		)
		(property "MPN" "CR0402-FX-2200GLF"
			(at 279.4 102.87 0)
			(effects
				(font
					(size 1.27 1.27)
					(thickness 0.15)
				)
				(justify left bottom)
				(hide yes)
			)
		)
		(property "Manufacturer" "Bourns"
			(at 279.4 105.41 0)
			(effects
				(font
					(size 1.27 1.27)
					(thickness 0.15)
				)
				(justify left bottom)
				(hide yes)
			)
		)
		(property "License" "Apache-2.0"
			(at 279.4 107.95 0)
			(effects
				(font
					(size 1.27 1.27)
					(thickness 0.15)
				)
				(justify left bottom)
				(hide yes)
			)
		)
		(property "Author" "Antmicro"
			(at 279.4 110.49 0)
			(effects
				(font
					(size 1.27 1.27)
					(thickness 0.15)
				)
				(justify left bottom)
				(hide yes)
			)
		)
		(property "Val" "220R"
			(at 264.16 81.28 0)
			(effects
				(font
					(size 1.27 1.27)
					(thickness 0.15)
				)
				(justify left)
			)
		)
		(property "Tolerance" "1%"
			(at 279.4 92.71 0)
			(effects
				(font
					(size 1.27 1.27)
				)
				(justify left bottom)
				(hide yes)
			)
		)
		(pin "1"
		)
		(pin "2"
		)
		(instances
			(project ""
				(path ""
					(reference "R36")
					(unit 1)
				)
			)
			(project "thunderbolt-to-10gbe-adapter"
				(path ""
					(reference "R210")
					(unit 1)
				)
			)
		)
	)
	(symbol
		(lib_id "antmicropower:+1V8")
		(at 142.24 95.25 0)
		(unit 1)
		(exclude_from_sim no)
		(in_bom yes)
		(on_board yes)
		(dnp no)
		(property "Reference" "#PWR0435"
			(at 157.48 97.79 0)
			(effects
				(font
					(size 1.27 1.27)
					(thickness 0.15)
				)
				(justify left bottom)
				(hide yes)
			)
		)
		(property "Value" "+1V88_CT"
			(at 142.24 91.44 0)
			(effects
				(font
					(size 1.27 1.27)
					(thickness 0.15)
				)
			)
		)
		(property "Footprint" ""
			(at 157.48 102.87 0)
			(effects
				(font
					(size 1.27 1.27)
					(thickness 0.15)
				)
				(justify left bottom)
				(hide yes)
			)
		)
		(property "Datasheet" ""
			(at 157.48 105.41 0)
			(effects
				(font
					(size 1.27 1.27)
					(thickness 0.15)
				)
				(justify left bottom)
				(hide yes)
			)
		)
		(property "Description" ""
			(at 142.24 95.25 0)
			(effects
				(font
					(size 1.27 1.27)
				)
				(hide yes)
			)
		)
		(property "Author" "Antmicro"
			(at 157.48 100.33 0)
			(effects
				(font
					(size 1.27 1.27)
					(thickness 0.15)
				)
				(justify left bottom)
				(hide yes)
			)
		)
		(property "License" "Apache-2.0"
			(at 157.48 102.87 0)
			(effects
				(font
					(size 1.27 1.27)
					(thickness 0.15)
				)
				(justify left bottom)
				(hide yes)
			)
		)
		(pin "1"
		)
		(instances
			(project "OCuLink to 10GbE adapter"
				(path ""
					(reference "#PWR069")
					(unit 1)
				)
			)
			(project "thunderbolt-to-10gbe-adapter"
				(path ""
					(reference "#PWR0435")
					(unit 1)
				)
			)
		)
	)
	(symbol
		(lib_id "antmicropower:+3V3")
		(at 228.6 213.36 0)
		(unit 1)
		(exclude_from_sim no)
		(in_bom yes)
		(on_board yes)
		(dnp no)
		(property "Reference" "#PWR0449"
			(at 243.84 213.36 0)
			(effects
				(font
					(size 1.27 1.27)
					(thickness 0.15)
				)
				(justify left bottom)
				(hide yes)
			)
		)
		(property "Value" "+3V3"
			(at 228.6 209.55 0)
			(effects
				(font
					(size 1.27 1.27)
					(thickness 0.15)
				)
			)
		)
		(property "Footprint" ""
			(at 243.84 220.98 0)
			(effects
				(font
					(size 1.27 1.27)
					(thickness 0.15)
				)
				(justify left bottom)
				(hide yes)
			)
		)
		(property "Datasheet" ""
			(at 243.84 223.52 0)
			(effects
				(font
					(size 1.27 1.27)
					(thickness 0.15)
				)
				(justify left bottom)
				(hide yes)
			)
		)
		(property "Description" ""
			(at 228.6 213.36 0)
			(effects
				(font
					(size 1.27 1.27)
				)
				(hide yes)
			)
		)
		(property "Author" "Antmicro"
			(at 243.84 215.9 0)
			(effects
				(font
					(size 1.27 1.27)
					(thickness 0.15)
				)
				(justify left bottom)
				(hide yes)
			)
		)
		(property "License" "Apache-2.0"
			(at 243.84 218.44 0)
			(effects
				(font
					(size 1.27 1.27)
					(thickness 0.15)
				)
				(justify left bottom)
				(hide yes)
			)
		)
		(pin "1"
		)
		(instances
			(project "OCuLink to 10GbE adapter"
				(path ""
					(reference "#PWR081")
					(unit 1)
				)
			)
			(project "thunderbolt-to-10gbe-adapter"
				(path ""
					(reference "#PWR0449")
					(unit 1)
				)
			)
		)
	)
	(symbol
		(lib_id "antmicroCapacitors0402:C_1u_25V_0402")
		(at 86.36 105.41 90)
		(unit 1)
		(exclude_from_sim no)
		(in_bom yes)
		(on_board yes)
		(dnp no)
		(property "Reference" "C290"
			(at 88.392 101.6 90)
			(effects
				(font
					(size 1.27 1.27)
					(thickness 0.15)
				)
				(justify right)
			)
		)
		(property "Value" "C_1u_25V_0402"
			(at 96.52 85.09 0)
			(effects
				(font
					(size 1.27 1.27)
					(thickness 0.15)
				)
				(justify left bottom)
				(hide yes)
			)
		)
		(property "Footprint" "antmicro-footprints:C_0402_1005Metric"
			(at 99.06 85.09 0)
			(effects
				(font
					(size 1.27 1.27)
					(thickness 0.15)
				)
				(justify left bottom)
				(hide yes)
			)
		)
		(property "Datasheet" "https://www.murata.com/products/productdetail?partno=GRM155R61E105KE11%23"
			(at 101.6 85.09 0)
			(effects
				(font
					(size 1.27 1.27)
					(thickness 0.15)
				)
				(justify left bottom)
				(hide yes)
			)
		)
		(property "Description" "SMD Multilayer Ceramic Capacitor, 1 µF, 25 V, 0402 [1005 Metric], ± 10%, X5R, GRM Series"
			(at 86.36 105.41 0)
			(effects
				(font
					(size 1.27 1.27)
				)
				(hide yes)
			)
		)
		(property "MPN" "GRM155R61E105KE11J"
			(at 104.14 85.09 0)
			(effects
				(font
					(size 1.27 1.27)
					(thickness 0.15)
				)
				(justify left bottom)
				(hide yes)
			)
		)
		(property "Manufacturer" "Murata"
			(at 106.68 85.09 0)
			(effects
				(font
					(size 1.27 1.27)
					(thickness 0.15)
				)
				(justify left bottom)
				(hide yes)
			)
		)
		(property "License" "Apache-2.0"
			(at 109.22 85.09 0)
			(effects
				(font
					(size 1.27 1.27)
					(thickness 0.15)
				)
				(justify left bottom)
				(hide yes)
			)
		)
		(property "Author" "Antmicro"
			(at 111.76 85.09 0)
			(effects
				(font
					(size 1.27 1.27)
					(thickness 0.15)
				)
				(justify left bottom)
				(hide yes)
			)
		)
		(property "Val" "1u"
			(at 88.392 104.14 90)
			(effects
				(font
					(size 1.27 1.27)
					(thickness 0.15)
				)
				(justify right)
			)
		)
		(property "Voltage" "25V"
			(at 114.3 85.09 0)
			(effects
				(font
					(size 1.27 1.27)
				)
				(justify left bottom)
				(hide yes)
			)
		)
		(property "Dielectric" "X5R"
			(at 116.84 85.09 0)
			(effects
				(font
					(size 1.27 1.27)
				)
				(justify left bottom)
				(hide yes)
			)
		)
		(pin "1"
		)
		(pin "2"
		)
		(instances
			(project "OCuLink to 10GbE adapter"
				(path ""
					(reference "C53")
					(unit 1)
				)
			)
			(project "thunderbolt-to-10gbe-adapter"
				(path ""
					(reference "C290")
					(unit 1)
				)
			)
		)
	)
	(symbol
		(lib_id "antmicropower:+1V8")
		(at 142.24 231.14 0)
		(unit 1)
		(exclude_from_sim no)
		(in_bom yes)
		(on_board yes)
		(dnp no)
		(property "Reference" "#PWR0436"
			(at 157.48 233.68 0)
			(effects
				(font
					(size 1.27 1.27)
					(thickness 0.15)
				)
				(justify left bottom)
				(hide yes)
			)
		)
		(property "Value" "+1V88_CT"
			(at 142.24 227.33 0)
			(effects
				(font
					(size 1.27 1.27)
					(thickness 0.15)
				)
			)
		)
		(property "Footprint" ""
			(at 157.48 238.76 0)
			(effects
				(font
					(size 1.27 1.27)
					(thickness 0.15)
				)
				(justify left bottom)
				(hide yes)
			)
		)
		(property "Datasheet" ""
			(at 157.48 241.3 0)
			(effects
				(font
					(size 1.27 1.27)
					(thickness 0.15)
				)
				(justify left bottom)
				(hide yes)
			)
		)
		(property "Description" ""
			(at 142.24 231.14 0)
			(effects
				(font
					(size 1.27 1.27)
				)
				(hide yes)
			)
		)
		(property "Author" "Antmicro"
			(at 157.48 236.22 0)
			(effects
				(font
					(size 1.27 1.27)
					(thickness 0.15)
				)
				(justify left bottom)
				(hide yes)
			)
		)
		(property "License" "Apache-2.0"
			(at 157.48 238.76 0)
			(effects
				(font
					(size 1.27 1.27)
					(thickness 0.15)
				)
				(justify left bottom)
				(hide yes)
			)
		)
		(pin "1"
		)
		(instances
			(project "OCuLink to 10GbE adapter"
				(path ""
					(reference "#PWR082")
					(unit 1)
				)
			)
			(project "thunderbolt-to-10gbe-adapter"
				(path ""
					(reference "#PWR0436")
					(unit 1)
				)
			)
		)
	)
	(symbol
		(lib_id "antmicroModularConnectorsJacksWithMagnetics:Bus_RJ45_JTH-0024NL")
		(at 204.47 62.23 0)
		(unit 1)
		(exclude_from_sim no)
		(in_bom yes)
		(on_board yes)
		(dnp no)
		(fields_autoplaced yes)
		(property "Reference" "J3"
			(at 215.265 54.61 0)
			(effects
				(font
					(size 1.27 1.27)
					(thickness 0.15)
				)
			)
		)
		(property "Value" "Bus_RJ45_JTH-0024NL"
			(at 240.03 67.31 0)
			(effects
				(font
					(size 1.27 1.27)
					(thickness 0.15)
				)
				(justify left bottom)
				(hide yes)
			)
		)
		(property "Footprint" "antmicro-footprints:RJ45_JTH-0024NL"
			(at 240.03 69.85 0)
			(effects
				(font
					(size 1.27 1.27)
					(thickness 0.15)
				)
				(justify left bottom)
				(hide yes)
			)
		)
		(property "Datasheet" "https://www.mouser.com/datasheet/2/447/JTH_0024NL-3072047.pdf"
			(at 240.03 72.39 0)
			(effects
				(font
					(size 1.27 1.27)
					(thickness 0.15)
				)
				(justify left bottom)
				(hide yes)
			)
		)
		(property "Description" "Modular Connectors / Ethernet Connectors 1X1 TAB DOWN W/LED'S ETHERNET (NON PoE)"
			(at 204.47 62.23 0)
			(effects
				(font
					(size 1.27 1.27)
				)
				(hide yes)
			)
		)
		(property "MPN" "JTH-0024NL"
			(at 215.265 57.15 0)
			(effects
				(font
					(size 1.27 1.27)
					(thickness 0.15)
				)
			)
		)
		(property "Manufacturer" "Pulse Electronics"
			(at 240.03 77.47 0)
			(effects
				(font
					(size 1.27 1.27)
					(thickness 0.15)
				)
				(justify left bottom)
				(hide yes)
			)
		)
		(property "Author" "Antmicro"
			(at 240.03 80.01 0)
			(effects
				(font
					(size 1.27 1.27)
					(thickness 0.15)
				)
				(justify left bottom)
				(hide yes)
			)
		)
		(property "License" "Apache-2.0"
			(at 240.03 82.55 0)
			(effects
				(font
					(size 1.27 1.27)
					(thickness 0.15)
				)
				(justify left bottom)
				(hide yes)
			)
		)
		(pin "8"
		)
		(pin "14"
		)
		(pin "9"
		)
		(pin "11"
		)
		(pin "10"
		)
		(pin "SH"
		)
		(pin "13"
		)
		(pin "17"
		)
		(pin "6"
		)
		(pin "12"
		)
		(pin "1"
		)
		(pin "2"
		)
		(pin "4"
		)
		(pin "5"
		)
		(pin "3"
		)
		(pin "7"
		)
		(pin "15"
		)
		(pin "16"
		)
		(instances
			(project ""
				(path ""
					(reference "J3")
					(unit 1)
				)
			)
			(project "thunderbolt-to-10gbe-adapter"
				(path ""
					(reference "J3")
					(unit 1)
				)
			)
		)
	)
	(symbol
		(lib_id "antmicropower:GND")
		(at 185.42 243.84 0)
		(unit 1)
		(exclude_from_sim no)
		(in_bom yes)
		(on_board yes)
		(dnp no)
		(property "Reference" "#PWR0444"
			(at 194.31 246.38 0)
			(effects
				(font
					(size 1.27 1.27)
					(thickness 0.15)
				)
				(justify left bottom)
				(hide yes)
			)
		)
		(property "Value" "GND"
			(at 185.42 247.65 0)
			(effects
				(font
					(size 1.27 1.27)
					(thickness 0.15)
				)
			)
		)
		(property "Footprint" ""
			(at 194.31 251.46 0)
			(effects
				(font
					(size 1.27 1.27)
					(thickness 0.15)
				)
				(justify left bottom)
				(hide yes)
			)
		)
		(property "Datasheet" ""
			(at 194.31 256.54 0)
			(effects
				(font
					(size 1.27 1.27)
					(thickness 0.15)
				)
				(justify left bottom)
				(hide yes)
			)
		)
		(property "Description" ""
			(at 185.42 243.84 0)
			(effects
				(font
					(size 1.27 1.27)
				)
				(hide yes)
			)
		)
		(property "Author" "Antmicro"
			(at 194.31 251.46 0)
			(effects
				(font
					(size 1.27 1.27)
					(thickness 0.15)
				)
				(justify left bottom)
				(hide yes)
			)
		)
		(property "License" "Apache-2.0"
			(at 194.31 254 0)
			(effects
				(font
					(size 1.27 1.27)
					(thickness 0.15)
				)
				(justify left bottom)
				(hide yes)
			)
		)
		(pin "1"
		)
		(instances
			(project "OCuLink to 10GbE adapter"
				(path ""
					(reference "#PWR086")
					(unit 1)
				)
			)
			(project "thunderbolt-to-10gbe-adapter"
				(path ""
					(reference "#PWR0444")
					(unit 1)
				)
			)
		)
	)
	(symbol
		(lib_id "antmicropower:GND")
		(at 154.94 107.95 0)
		(unit 1)
		(exclude_from_sim no)
		(in_bom yes)
		(on_board yes)
		(dnp no)
		(property "Reference" "#PWR0437"
			(at 163.83 110.49 0)
			(effects
				(font
					(size 1.27 1.27)
					(thickness 0.15)
				)
				(justify left bottom)
				(hide yes)
			)
		)
		(property "Value" "GND"
			(at 154.94 111.76 0)
			(effects
				(font
					(size 1.27 1.27)
					(thickness 0.15)
				)
			)
		)
		(property "Footprint" ""
			(at 163.83 115.57 0)
			(effects
				(font
					(size 1.27 1.27)
					(thickness 0.15)
				)
				(justify left bottom)
				(hide yes)
			)
		)
		(property "Datasheet" ""
			(at 163.83 120.65 0)
			(effects
				(font
					(size 1.27 1.27)
					(thickness 0.15)
				)
				(justify left bottom)
				(hide yes)
			)
		)
		(property "Description" ""
			(at 154.94 107.95 0)
			(effects
				(font
					(size 1.27 1.27)
				)
				(hide yes)
			)
		)
		(property "Author" "Antmicro"
			(at 163.83 115.57 0)
			(effects
				(font
					(size 1.27 1.27)
					(thickness 0.15)
				)
				(justify left bottom)
				(hide yes)
			)
		)
		(property "License" "Apache-2.0"
			(at 163.83 118.11 0)
			(effects
				(font
					(size 1.27 1.27)
					(thickness 0.15)
				)
				(justify left bottom)
				(hide yes)
			)
		)
		(pin "1"
		)
		(instances
			(project "OCuLink to 10GbE adapter"
				(path ""
					(reference "#PWR074")
					(unit 1)
				)
			)
			(project "thunderbolt-to-10gbe-adapter"
				(path ""
					(reference "#PWR0437")
					(unit 1)
				)
			)
		)
	)
	(symbol
		(lib_id "antmicropower:+3V3")
		(at 228.6 77.47 0)
		(unit 1)
		(exclude_from_sim no)
		(in_bom yes)
		(on_board yes)
		(dnp no)
		(property "Reference" "#PWR0447"
			(at 243.84 77.47 0)
			(effects
				(font
					(size 1.27 1.27)
					(thickness 0.15)
				)
				(justify left bottom)
				(hide yes)
			)
		)
		(property "Value" "+3V3"
			(at 228.6 73.66 0)
			(effects
				(font
					(size 1.27 1.27)
					(thickness 0.15)
				)
			)
		)
		(property "Footprint" ""
			(at 243.84 85.09 0)
			(effects
				(font
					(size 1.27 1.27)
					(thickness 0.15)
				)
				(justify left bottom)
				(hide yes)
			)
		)
		(property "Datasheet" ""
			(at 243.84 87.63 0)
			(effects
				(font
					(size 1.27 1.27)
					(thickness 0.15)
				)
				(justify left bottom)
				(hide yes)
			)
		)
		(property "Description" ""
			(at 228.6 77.47 0)
			(effects
				(font
					(size 1.27 1.27)
				)
				(hide yes)
			)
		)
		(property "Author" "Antmicro"
			(at 243.84 80.01 0)
			(effects
				(font
					(size 1.27 1.27)
					(thickness 0.15)
				)
				(justify left bottom)
				(hide yes)
			)
		)
		(property "License" "Apache-2.0"
			(at 243.84 82.55 0)
			(effects
				(font
					(size 1.27 1.27)
					(thickness 0.15)
				)
				(justify left bottom)
				(hide yes)
			)
		)
		(pin "1"
		)
		(instances
			(project "OCuLink to 10GbE adapter"
				(path ""
					(reference "#PWR066")
					(unit 1)
				)
			)
			(project "thunderbolt-to-10gbe-adapter"
				(path ""
					(reference "#PWR0447")
					(unit 1)
				)
			)
		)
	)
	(symbol
		(lib_id "antmicroCapacitors0603:C_22u_16V_0603")
		(at 71.12 105.41 90)
		(unit 1)
		(exclude_from_sim no)
		(in_bom yes)
		(on_board yes)
		(dnp no)
		(property "Reference" "C289"
			(at 73.152 101.6 90)
			(effects
				(font
					(size 1.27 1.27)
					(thickness 0.15)
				)
				(justify right)
			)
		)
		(property "Value" "C_22u_16V_0603"
			(at 81.28 85.09 0)
			(effects
				(font
					(size 1.27 1.27)
					(thickness 0.15)
				)
				(justify left bottom)
				(hide yes)
			)
		)
		(property "Footprint" "antmicro-footprints:C_0603_1608Metric_EIA"
			(at 83.82 85.09 0)
			(effects
				(font
					(size 1.27 1.27)
					(thickness 0.15)
				)
				(justify left bottom)
				(hide yes)
			)
		)
		(property "Datasheet" "https://product.samsungsem.com/mlcc/CL10A226MO7JZN.do"
			(at 86.36 85.09 0)
			(effects
				(font
					(size 1.27 1.27)
					(thickness 0.15)
				)
				(justify left bottom)
				(hide yes)
			)
		)
		(property "Description" "SMD Multilayer Ceramic Capacitor"
			(at 71.12 105.41 0)
			(effects
				(font
					(size 1.27 1.27)
				)
				(hide yes)
			)
		)
		(property "MPN" "CL10A226MO7JZNC"
			(at 88.9 85.09 0)
			(effects
				(font
					(size 1.27 1.27)
					(thickness 0.15)
				)
				(justify left bottom)
				(hide yes)
			)
		)
		(property "Manufacturer" "Samsung Electro-Mechanics"
			(at 91.44 85.09 0)
			(effects
				(font
					(size 1.27 1.27)
					(thickness 0.15)
				)
				(justify left bottom)
				(hide yes)
			)
		)
		(property "License" "Apache-2.0"
			(at 93.98 85.09 0)
			(effects
				(font
					(size 1.27 1.27)
					(thickness 0.15)
				)
				(justify left bottom)
				(hide yes)
			)
		)
		(property "Author" "Antmicro"
			(at 96.52 85.09 0)
			(effects
				(font
					(size 1.27 1.27)
					(thickness 0.15)
				)
				(justify left bottom)
				(hide yes)
			)
		)
		(property "Val" "22u"
			(at 73.152 104.14 90)
			(effects
				(font
					(size 1.27 1.27)
					(thickness 0.15)
				)
				(justify right)
			)
		)
		(property "Voltage" "16V"
			(at 99.06 85.09 0)
			(effects
				(font
					(size 1.27 1.27)
				)
				(justify left bottom)
				(hide yes)
			)
		)
		(property "Dielectric" ""
			(at 101.6 85.09 0)
			(effects
				(font
					(size 1.27 1.27)
				)
				(justify left bottom)
				(hide yes)
			)
		)
		(pin "1"
		)
		(pin "2"
		)
		(instances
			(project ""
				(path ""
					(reference "C52")
					(unit 1)
				)
			)
			(project "thunderbolt-to-10gbe-adapter"
				(path ""
					(reference "C289")
					(unit 1)
				)
			)
		)
	)
	(symbol
		(lib_id "antmicropower:GND")
		(at 228.6 243.84 0)
		(unit 1)
		(exclude_from_sim no)
		(in_bom yes)
		(on_board yes)
		(dnp no)
		(property "Reference" "#PWR0450"
			(at 237.49 246.38 0)
			(effects
				(font
					(size 1.27 1.27)
					(thickness 0.15)
				)
				(justify left bottom)
				(hide yes)
			)
		)
		(property "Value" "GND"
			(at 228.6 247.65 0)
			(effects
				(font
					(size 1.27 1.27)
					(thickness 0.15)
				)
			)
		)
		(property "Footprint" ""
			(at 237.49 251.46 0)
			(effects
				(font
					(size 1.27 1.27)
					(thickness 0.15)
				)
				(justify left bottom)
				(hide yes)
			)
		)
		(property "Datasheet" ""
			(at 237.49 256.54 0)
			(effects
				(font
					(size 1.27 1.27)
					(thickness 0.15)
				)
				(justify left bottom)
				(hide yes)
			)
		)
		(property "Description" ""
			(at 228.6 243.84 0)
			(effects
				(font
					(size 1.27 1.27)
				)
				(hide yes)
			)
		)
		(property "Author" "Antmicro"
			(at 237.49 251.46 0)
			(effects
				(font
					(size 1.27 1.27)
					(thickness 0.15)
				)
				(justify left bottom)
				(hide yes)
			)
		)
		(property "License" "Apache-2.0"
			(at 237.49 254 0)
			(effects
				(font
					(size 1.27 1.27)
					(thickness 0.15)
				)
				(justify left bottom)
				(hide yes)
			)
		)
		(pin "1"
		)
		(instances
			(project "OCuLink to 10GbE adapter"
				(path ""
					(reference "#PWR088")
					(unit 1)
				)
			)
			(project "thunderbolt-to-10gbe-adapter"
				(path ""
					(reference "#PWR0450")
					(unit 1)
				)
			)
		)
	)
	(symbol
		(lib_id "antmicroCapacitors0402:C_470p_0402")
		(at 254 102.87 90)
		(unit 1)
		(exclude_from_sim no)
		(in_bom yes)
		(on_board yes)
		(dnp no)
		(property "Reference" "C306"
			(at 256.032 99.06 90)
			(effects
				(font
					(size 1.27 1.27)
					(thickness 0.15)
				)
				(justify right)
			)
		)
		(property "Value" "C_470p_0402"
			(at 264.16 82.55 0)
			(effects
				(font
					(size 1.27 1.27)
					(thickness 0.15)
				)
				(justify left bottom)
				(hide yes)
			)
		)
		(property "Footprint" "antmicro-footprints:C_0402_1005Metric"
			(at 266.7 82.55 0)
			(effects
				(font
					(size 1.27 1.27)
					(thickness 0.15)
				)
				(justify left bottom)
				(hide yes)
			)
		)
		(property "Datasheet" "https://www.passivecomponent.com/wp-content/uploads/datasheet/WTC_MLCC_General_Purpose.pdf"
			(at 269.24 82.55 0)
			(effects
				(font
					(size 1.27 1.27)
					(thickness 0.15)
				)
				(justify left bottom)
				(hide yes)
			)
		)
		(property "Description" "SMD Multilayer Ceramic Capacitor, General Purpose, 470 pF, 25 V, 0402 [1005 Metric], ± 10%, X7R"
			(at 254 102.87 0)
			(effects
				(font
					(size 1.27 1.27)
				)
				(hide yes)
			)
		)
		(property "MPN" "0402B471K250CT"
			(at 271.78 82.55 0)
			(effects
				(font
					(size 1.27 1.27)
					(thickness 0.15)
				)
				(justify left bottom)
				(hide yes)
			)
		)
		(property "Manufacturer" "Walsin"
			(at 274.32 82.55 0)
			(effects
				(font
					(size 1.27 1.27)
					(thickness 0.15)
				)
				(justify left bottom)
				(hide yes)
			)
		)
		(property "License" "Apache-2.0"
			(at 276.86 82.55 0)
			(effects
				(font
					(size 1.27 1.27)
					(thickness 0.15)
				)
				(justify left bottom)
				(hide yes)
			)
		)
		(property "Author" "Antmicro"
			(at 279.4 82.55 0)
			(effects
				(font
					(size 1.27 1.27)
					(thickness 0.15)
				)
				(justify left bottom)
				(hide yes)
			)
		)
		(property "Val" "470p"
			(at 256.032 101.6 90)
			(effects
				(font
					(size 1.27 1.27)
					(thickness 0.15)
				)
				(justify right)
			)
		)
		(property "Voltage" "25V"
			(at 281.94 82.55 0)
			(effects
				(font
					(size 1.27 1.27)
				)
				(justify left bottom)
				(hide yes)
			)
		)
		(property "Dielectric" "X7R"
			(at 284.48 82.55 0)
			(effects
				(font
					(size 1.27 1.27)
				)
				(justify left bottom)
				(hide yes)
			)
		)
		(pin "2"
		)
		(pin "1"
		)
		(instances
			(project "OCuLink to 10GbE adapter"
				(path ""
					(reference "C50")
					(unit 1)
				)
			)
			(project "thunderbolt-to-10gbe-adapter"
				(path ""
					(reference "C306")
					(unit 1)
				)
			)
		)
	)
	(symbol
		(lib_id "antmicropower:GND")
		(at 154.94 243.84 0)
		(unit 1)
		(exclude_from_sim no)
		(in_bom yes)
		(on_board yes)
		(dnp no)
		(property "Reference" "#PWR0438"
			(at 163.83 246.38 0)
			(effects
				(font
					(size 1.27 1.27)
					(thickness 0.15)
				)
				(justify left bottom)
				(hide yes)
			)
		)
		(property "Value" "GND"
			(at 154.94 247.65 0)
			(effects
				(font
					(size 1.27 1.27)
					(thickness 0.15)
				)
			)
		)
		(property "Footprint" ""
			(at 163.83 251.46 0)
			(effects
				(font
					(size 1.27 1.27)
					(thickness 0.15)
				)
				(justify left bottom)
				(hide yes)
			)
		)
		(property "Datasheet" ""
			(at 163.83 256.54 0)
			(effects
				(font
					(size 1.27 1.27)
					(thickness 0.15)
				)
				(justify left bottom)
				(hide yes)
			)
		)
		(property "Description" ""
			(at 154.94 243.84 0)
			(effects
				(font
					(size 1.27 1.27)
				)
				(hide yes)
			)
		)
		(property "Author" "Antmicro"
			(at 163.83 251.46 0)
			(effects
				(font
					(size 1.27 1.27)
					(thickness 0.15)
				)
				(justify left bottom)
				(hide yes)
			)
		)
		(property "License" "Apache-2.0"
			(at 163.83 254 0)
			(effects
				(font
					(size 1.27 1.27)
					(thickness 0.15)
				)
				(justify left bottom)
				(hide yes)
			)
		)
		(pin "1"
		)
		(instances
			(project "OCuLink to 10GbE adapter"
				(path ""
					(reference "#PWR083")
					(unit 1)
				)
			)
			(project "thunderbolt-to-10gbe-adapter"
				(path ""
					(reference "#PWR0438")
					(unit 1)
				)
			)
		)
	)
	(symbol
		(lib_id "antmicroCapacitors0402:C_1u_25V_0402")
		(at 167.64 105.41 90)
		(unit 1)
		(exclude_from_sim no)
		(in_bom yes)
		(on_board yes)
		(dnp no)
		(property "Reference" "C294"
			(at 169.672 101.6 90)
			(effects
				(font
					(size 1.27 1.27)
					(thickness 0.15)
				)
				(justify right)
			)
		)
		(property "Value" "C_1u_25V_0402"
			(at 177.8 85.09 0)
			(effects
				(font
					(size 1.27 1.27)
					(thickness 0.15)
				)
				(justify left bottom)
				(hide yes)
			)
		)
		(property "Footprint" "antmicro-footprints:C_0402_1005Metric"
			(at 180.34 85.09 0)
			(effects
				(font
					(size 1.27 1.27)
					(thickness 0.15)
				)
				(justify left bottom)
				(hide yes)
			)
		)
		(property "Datasheet" "https://www.murata.com/products/productdetail?partno=GRM155R61E105KE11%23"
			(at 182.88 85.09 0)
			(effects
				(font
					(size 1.27 1.27)
					(thickness 0.15)
				)
				(justify left bottom)
				(hide yes)
			)
		)
		(property "Description" "SMD Multilayer Ceramic Capacitor, 1 µF, 25 V, 0402 [1005 Metric], ± 10%, X5R, GRM Series"
			(at 167.64 105.41 0)
			(effects
				(font
					(size 1.27 1.27)
				)
				(hide yes)
			)
		)
		(property "MPN" "GRM155R61E105KE11J"
			(at 185.42 85.09 0)
			(effects
				(font
					(size 1.27 1.27)
					(thickness 0.15)
				)
				(justify left bottom)
				(hide yes)
			)
		)
		(property "Manufacturer" "Murata"
			(at 187.96 85.09 0)
			(effects
				(font
					(size 1.27 1.27)
					(thickness 0.15)
				)
				(justify left bottom)
				(hide yes)
			)
		)
		(property "License" "Apache-2.0"
			(at 190.5 85.09 0)
			(effects
				(font
					(size 1.27 1.27)
					(thickness 0.15)
				)
				(justify left bottom)
				(hide yes)
			)
		)
		(property "Author" "Antmicro"
			(at 193.04 85.09 0)
			(effects
				(font
					(size 1.27 1.27)
					(thickness 0.15)
				)
				(justify left bottom)
				(hide yes)
			)
		)
		(property "Val" "1u"
			(at 169.672 104.14 90)
			(effects
				(font
					(size 1.27 1.27)
					(thickness 0.15)
				)
				(justify right)
			)
		)
		(property "Voltage" "25V"
			(at 195.58 85.09 0)
			(effects
				(font
					(size 1.27 1.27)
				)
				(justify left bottom)
				(hide yes)
			)
		)
		(property "Dielectric" "X5R"
			(at 198.12 85.09 0)
			(effects
				(font
					(size 1.27 1.27)
				)
				(justify left bottom)
				(hide yes)
			)
		)
		(pin "1"
		)
		(pin "2"
		)
		(instances
			(project "OCuLink to 10GbE adapter"
				(path ""
					(reference "C56")
					(unit 1)
				)
			)
			(project "thunderbolt-to-10gbe-adapter"
				(path ""
					(reference "C294")
					(unit 1)
				)
			)
		)
	)
	(symbol
		(lib_id "antmicropower:GND")
		(at 194.31 107.95 0)
		(unit 1)
		(exclude_from_sim no)
		(in_bom yes)
		(on_board yes)
		(dnp no)
		(property "Reference" "#PWR0445"
			(at 203.2 110.49 0)
			(effects
				(font
					(size 1.27 1.27)
					(thickness 0.15)
				)
				(justify left bottom)
				(hide yes)
			)
		)
		(property "Value" "GND"
			(at 194.31 111.76 0)
			(effects
				(font
					(size 1.27 1.27)
					(thickness 0.15)
				)
			)
		)
		(property "Footprint" ""
			(at 203.2 115.57 0)
			(effects
				(font
					(size 1.27 1.27)
					(thickness 0.15)
				)
				(justify left bottom)
				(hide yes)
			)
		)
		(property "Datasheet" ""
			(at 203.2 120.65 0)
			(effects
				(font
					(size 1.27 1.27)
					(thickness 0.15)
				)
				(justify left bottom)
				(hide yes)
			)
		)
		(property "Description" ""
			(at 194.31 107.95 0)
			(effects
				(font
					(size 1.27 1.27)
				)
				(hide yes)
			)
		)
		(property "Author" "Antmicro"
			(at 203.2 115.57 0)
			(effects
				(font
					(size 1.27 1.27)
					(thickness 0.15)
				)
				(justify left bottom)
				(hide yes)
			)
		)
		(property "License" "Apache-2.0"
			(at 203.2 118.11 0)
			(effects
				(font
					(size 1.27 1.27)
					(thickness 0.15)
				)
				(justify left bottom)
				(hide yes)
			)
		)
		(pin "1"
		)
		(instances
			(project "OCuLink to 10GbE adapter"
				(path ""
					(reference "#PWR078")
					(unit 1)
				)
			)
			(project "thunderbolt-to-10gbe-adapter"
				(path ""
					(reference "#PWR0445")
					(unit 1)
				)
			)
		)
	)
	(symbol
		(lib_id "antmicroCapacitors0402:C_470p_0402")
		(at 254 238.76 90)
		(unit 1)
		(exclude_from_sim no)
		(in_bom yes)
		(on_board yes)
		(dnp no)
		(property "Reference" "C307"
			(at 256.032 234.95 90)
			(effects
				(font
					(size 1.27 1.27)
					(thickness 0.15)
				)
				(justify right)
			)
		)
		(property "Value" "C_470p_0402"
			(at 264.16 218.44 0)
			(effects
				(font
					(size 1.27 1.27)
					(thickness 0.15)
				)
				(justify left bottom)
				(hide yes)
			)
		)
		(property "Footprint" "antmicro-footprints:C_0402_1005Metric"
			(at 266.7 218.44 0)
			(effects
				(font
					(size 1.27 1.27)
					(thickness 0.15)
				)
				(justify left bottom)
				(hide yes)
			)
		)
		(property "Datasheet" "https://www.passivecomponent.com/wp-content/uploads/datasheet/WTC_MLCC_General_Purpose.pdf"
			(at 269.24 218.44 0)
			(effects
				(font
					(size 1.27 1.27)
					(thickness 0.15)
				)
				(justify left bottom)
				(hide yes)
			)
		)
		(property "Description" "SMD Multilayer Ceramic Capacitor, General Purpose, 470 pF, 25 V, 0402 [1005 Metric], ± 10%, X7R"
			(at 254 238.76 0)
			(effects
				(font
					(size 1.27 1.27)
				)
				(hide yes)
			)
		)
		(property "MPN" "0402B471K250CT"
			(at 271.78 218.44 0)
			(effects
				(font
					(size 1.27 1.27)
					(thickness 0.15)
				)
				(justify left bottom)
				(hide yes)
			)
		)
		(property "Manufacturer" "Walsin"
			(at 274.32 218.44 0)
			(effects
				(font
					(size 1.27 1.27)
					(thickness 0.15)
				)
				(justify left bottom)
				(hide yes)
			)
		)
		(property "License" "Apache-2.0"
			(at 276.86 218.44 0)
			(effects
				(font
					(size 1.27 1.27)
					(thickness 0.15)
				)
				(justify left bottom)
				(hide yes)
			)
		)
		(property "Author" "Antmicro"
			(at 279.4 218.44 0)
			(effects
				(font
					(size 1.27 1.27)
					(thickness 0.15)
				)
				(justify left bottom)
				(hide yes)
			)
		)
		(property "Val" "470p"
			(at 256.032 237.49 90)
			(effects
				(font
					(size 1.27 1.27)
					(thickness 0.15)
				)
				(justify right)
			)
		)
		(property "Voltage" "25V"
			(at 281.94 218.44 0)
			(effects
				(font
					(size 1.27 1.27)
				)
				(justify left bottom)
				(hide yes)
			)
		)
		(property "Dielectric" "X7R"
			(at 284.48 218.44 0)
			(effects
				(font
					(size 1.27 1.27)
				)
				(justify left bottom)
				(hide yes)
			)
		)
		(pin "2"
		)
		(pin "1"
		)
		(instances
			(project "OCuLink to 10GbE adapter"
				(path ""
					(reference "C62")
					(unit 1)
				)
			)
			(project "thunderbolt-to-10gbe-adapter"
				(path ""
					(reference "C307")
					(unit 1)
				)
			)
		)
	)
	(symbol
		(lib_id "antmicroCapacitors0402:C_1u_25V_0402")
		(at 194.31 241.3 90)
		(unit 1)
		(exclude_from_sim no)
		(in_bom yes)
		(on_board yes)
		(dnp no)
		(property "Reference" "C301"
			(at 196.342 237.49 90)
			(effects
				(font
					(size 1.27 1.27)
					(thickness 0.15)
				)
				(justify right)
			)
		)
		(property "Value" "C_1u_25V_0402"
			(at 204.47 220.98 0)
			(effects
				(font
					(size 1.27 1.27)
					(thickness 0.15)
				)
				(justify left bottom)
				(hide yes)
			)
		)
		(property "Footprint" "antmicro-footprints:C_0402_1005Metric"
			(at 207.01 220.98 0)
			(effects
				(font
					(size 1.27 1.27)
					(thickness 0.15)
				)
				(justify left bottom)
				(hide yes)
			)
		)
		(property "Datasheet" "https://www.murata.com/products/productdetail?partno=GRM155R61E105KE11%23"
			(at 209.55 220.98 0)
			(effects
				(font
					(size 1.27 1.27)
					(thickness 0.15)
				)
				(justify left bottom)
				(hide yes)
			)
		)
		(property "Description" "SMD Multilayer Ceramic Capacitor, 1 µF, 25 V, 0402 [1005 Metric], ± 10%, X5R, GRM Series"
			(at 194.31 241.3 0)
			(effects
				(font
					(size 1.27 1.27)
				)
				(hide yes)
			)
		)
		(property "MPN" "GRM155R61E105KE11J"
			(at 212.09 220.98 0)
			(effects
				(font
					(size 1.27 1.27)
					(thickness 0.15)
				)
				(justify left bottom)
				(hide yes)
			)
		)
		(property "Manufacturer" "Murata"
			(at 214.63 220.98 0)
			(effects
				(font
					(size 1.27 1.27)
					(thickness 0.15)
				)
				(justify left bottom)
				(hide yes)
			)
		)
		(property "License" "Apache-2.0"
			(at 217.17 220.98 0)
			(effects
				(font
					(size 1.27 1.27)
					(thickness 0.15)
				)
				(justify left bottom)
				(hide yes)
			)
		)
		(property "Author" "Antmicro"
			(at 219.71 220.98 0)
			(effects
				(font
					(size 1.27 1.27)
					(thickness 0.15)
				)
				(justify left bottom)
				(hide yes)
			)
		)
		(property "Val" "1u"
			(at 196.342 240.03 90)
			(effects
				(font
					(size 1.27 1.27)
					(thickness 0.15)
				)
				(justify right)
			)
		)
		(property "Voltage" "25V"
			(at 222.25 220.98 0)
			(effects
				(font
					(size 1.27 1.27)
				)
				(justify left bottom)
				(hide yes)
			)
		)
		(property "Dielectric" "X5R"
			(at 224.79 220.98 0)
			(effects
				(font
					(size 1.27 1.27)
				)
				(justify left bottom)
				(hide yes)
			)
		)
		(pin "1"
		)
		(pin "2"
		)
		(instances
			(project "OCuLink to 10GbE adapter"
				(path ""
					(reference "C67")
					(unit 1)
				)
			)
			(project "thunderbolt-to-10gbe-adapter"
				(path ""
					(reference "C301")
					(unit 1)
				)
			)
		)
	)
	(symbol
		(lib_id "antmicroResistors0402:R_220R_0402")
		(at 259.08 218.44 0)
		(unit 1)
		(exclude_from_sim no)
		(in_bom yes)
		(on_board yes)
		(dnp no)
		(property "Reference" "R213"
			(at 259.08 217.17 0)
			(effects
				(font
					(size 1.27 1.27)
					(thickness 0.15)
				)
				(justify right)
			)
		)
		(property "Value" "R_220R_0402"
			(at 279.4 231.14 0)
			(effects
				(font
					(size 1.27 1.27)
					(thickness 0.15)
				)
				(justify left bottom)
				(hide yes)
			)
		)
		(property "Footprint" "antmicro-footprints:R_0402_1005Metric"
			(at 279.4 233.68 0)
			(effects
				(font
					(size 1.27 1.27)
					(thickness 0.15)
				)
				(justify left bottom)
				(hide yes)
			)
		)
		(property "Datasheet" "https://www.bourns.com/docs/product-datasheets/cr.pdf"
			(at 279.4 236.22 0)
			(effects
				(font
					(size 1.27 1.27)
					(thickness 0.15)
				)
				(justify left bottom)
				(hide yes)
			)
		)
		(property "Description" "SMD Chip Resistor, 220 ohm, ± 1%, 62.5 mW, 0402 [1005 Metric], Thick Film, General Purpose"
			(at 259.08 218.44 0)
			(effects
				(font
					(size 1.27 1.27)
				)
				(hide yes)
			)
		)
		(property "MPN" "CR0402-FX-2200GLF"
			(at 279.4 238.76 0)
			(effects
				(font
					(size 1.27 1.27)
					(thickness 0.15)
				)
				(justify left bottom)
				(hide yes)
			)
		)
		(property "Manufacturer" "Bourns"
			(at 279.4 241.3 0)
			(effects
				(font
					(size 1.27 1.27)
					(thickness 0.15)
				)
				(justify left bottom)
				(hide yes)
			)
		)
		(property "License" "Apache-2.0"
			(at 279.4 243.84 0)
			(effects
				(font
					(size 1.27 1.27)
					(thickness 0.15)
				)
				(justify left bottom)
				(hide yes)
			)
		)
		(property "Author" "Antmicro"
			(at 279.4 246.38 0)
			(effects
				(font
					(size 1.27 1.27)
					(thickness 0.15)
				)
				(justify left bottom)
				(hide yes)
			)
		)
		(property "Val" "220R"
			(at 264.16 217.17 0)
			(effects
				(font
					(size 1.27 1.27)
					(thickness 0.15)
				)
				(justify left)
			)
		)
		(property "Tolerance" "1%"
			(at 279.4 228.6 0)
			(effects
				(font
					(size 1.27 1.27)
				)
				(justify left bottom)
				(hide yes)
			)
		)
		(pin "1"
		)
		(pin "2"
		)
		(instances
			(project "OCuLink to 10GbE adapter"
				(path ""
					(reference "R39")
					(unit 1)
				)
			)
			(project "thunderbolt-to-10gbe-adapter"
				(path ""
					(reference "R213")
					(unit 1)
				)
			)
		)
	)
	(symbol
		(lib_id "antmicropower:GND")
		(at 176.53 107.95 0)
		(unit 1)
		(exclude_from_sim no)
		(in_bom yes)
		(on_board yes)
		(dnp no)
		(property "Reference" "#PWR0441"
			(at 185.42 110.49 0)
			(effects
				(font
					(size 1.27 1.27)
					(thickness 0.15)
				)
				(justify left bottom)
				(hide yes)
			)
		)
		(property "Value" "GND"
			(at 176.53 111.76 0)
			(effects
				(font
					(size 1.27 1.27)
					(thickness 0.15)
				)
			)
		)
		(property "Footprint" ""
			(at 185.42 115.57 0)
			(effects
				(font
					(size 1.27 1.27)
					(thickness 0.15)
				)
				(justify left bottom)
				(hide yes)
			)
		)
		(property "Datasheet" ""
			(at 185.42 120.65 0)
			(effects
				(font
					(size 1.27 1.27)
					(thickness 0.15)
				)
				(justify left bottom)
				(hide yes)
			)
		)
		(property "Description" ""
			(at 176.53 107.95 0)
			(effects
				(font
					(size 1.27 1.27)
				)
				(hide yes)
			)
		)
		(property "Author" "Antmicro"
			(at 185.42 115.57 0)
			(effects
				(font
					(size 1.27 1.27)
					(thickness 0.15)
				)
				(justify left bottom)
				(hide yes)
			)
		)
		(property "License" "Apache-2.0"
			(at 185.42 118.11 0)
			(effects
				(font
					(size 1.27 1.27)
					(thickness 0.15)
				)
				(justify left bottom)
				(hide yes)
			)
		)
		(pin "1"
		)
		(instances
			(project "OCuLink to 10GbE adapter"
				(path ""
					(reference "#PWR076")
					(unit 1)
				)
			)
			(project "thunderbolt-to-10gbe-adapter"
				(path ""
					(reference "#PWR0441")
					(unit 1)
				)
			)
		)
	)
	(symbol
		(lib_id "antmicroCapacitors0402:C_1u_25V_0402")
		(at 176.53 241.3 90)
		(unit 1)
		(exclude_from_sim no)
		(in_bom yes)
		(on_board yes)
		(dnp no)
		(property "Reference" "C297"
			(at 178.562 237.49 90)
			(effects
				(font
					(size 1.27 1.27)
					(thickness 0.15)
				)
				(justify right)
			)
		)
		(property "Value" "C_1u_25V_0402"
			(at 186.69 220.98 0)
			(effects
				(font
					(size 1.27 1.27)
					(thickness 0.15)
				)
				(justify left bottom)
				(hide yes)
			)
		)
		(property "Footprint" "antmicro-footprints:C_0402_1005Metric"
			(at 189.23 220.98 0)
			(effects
				(font
					(size 1.27 1.27)
					(thickness 0.15)
				)
				(justify left bottom)
				(hide yes)
			)
		)
		(property "Datasheet" "https://www.murata.com/products/productdetail?partno=GRM155R61E105KE11%23"
			(at 191.77 220.98 0)
			(effects
				(font
					(size 1.27 1.27)
					(thickness 0.15)
				)
				(justify left bottom)
				(hide yes)
			)
		)
		(property "Description" "SMD Multilayer Ceramic Capacitor, 1 µF, 25 V, 0402 [1005 Metric], ± 10%, X5R, GRM Series"
			(at 176.53 241.3 0)
			(effects
				(font
					(size 1.27 1.27)
				)
				(hide yes)
			)
		)
		(property "MPN" "GRM155R61E105KE11J"
			(at 194.31 220.98 0)
			(effects
				(font
					(size 1.27 1.27)
					(thickness 0.15)
				)
				(justify left bottom)
				(hide yes)
			)
		)
		(property "Manufacturer" "Murata"
			(at 196.85 220.98 0)
			(effects
				(font
					(size 1.27 1.27)
					(thickness 0.15)
				)
				(justify left bottom)
				(hide yes)
			)
		)
		(property "License" "Apache-2.0"
			(at 199.39 220.98 0)
			(effects
				(font
					(size 1.27 1.27)
					(thickness 0.15)
				)
				(justify left bottom)
				(hide yes)
			)
		)
		(property "Author" "Antmicro"
			(at 201.93 220.98 0)
			(effects
				(font
					(size 1.27 1.27)
					(thickness 0.15)
				)
				(justify left bottom)
				(hide yes)
			)
		)
		(property "Val" "1u"
			(at 178.562 240.03 90)
			(effects
				(font
					(size 1.27 1.27)
					(thickness 0.15)
				)
				(justify right)
			)
		)
		(property "Voltage" "25V"
			(at 204.47 220.98 0)
			(effects
				(font
					(size 1.27 1.27)
				)
				(justify left bottom)
				(hide yes)
			)
		)
		(property "Dielectric" "X5R"
			(at 207.01 220.98 0)
			(effects
				(font
					(size 1.27 1.27)
				)
				(justify left bottom)
				(hide yes)
			)
		)
		(pin "1"
		)
		(pin "2"
		)
		(instances
			(project "OCuLink to 10GbE adapter"
				(path ""
					(reference "C65")
					(unit 1)
				)
			)
			(project "thunderbolt-to-10gbe-adapter"
				(path ""
					(reference "C297")
					(unit 1)
				)
			)
		)
	)
	(symbol
		(lib_id "antmicroFixedInductors:L_2n4_0.85A_0402")
		(at 147.32 97.79 0)
		(unit 1)
		(exclude_from_sim no)
		(in_bom yes)
		(on_board yes)
		(dnp no)
		(property "Reference" "L12"
			(at 149.86 93.218 0)
			(effects
				(font
					(size 1.27 1.27)
					(thickness 0.15)
				)
			)
		)
		(property "Value" "L_2n4_0.85A_0402"
			(at 161.29 100.33 0)
			(effects
				(font
					(size 1.27 1.27)
					(thickness 0.15)
				)
				(justify left bottom)
				(hide yes)
			)
		)
		(property "Footprint" "antmicro-footprints:L_0402_1005Metric"
			(at 161.29 105.41 0)
			(effects
				(font
					(size 1.27 1.27)
					(thickness 0.15)
				)
				(justify left bottom)
				(hide yes)
			)
		)
		(property "Datasheet" "https://www.murata.com/products/productdetail?partno=LQW15AN2N4B00%23"
			(at 161.29 107.95 0)
			(effects
				(font
					(size 1.27 1.27)
					(thickness 0.15)
				)
				(justify left bottom)
				(hide yes)
			)
		)
		(property "Description" "Wirewound Inductor, 2.4 nH, 0.05 ohm, 15 GHz, 850 mA, 0402 [1005 Metric], LQW15AN"
			(at 147.32 97.79 0)
			(effects
				(font
					(size 1.27 1.27)
				)
				(hide yes)
			)
		)
		(property "Val" "2n4/0.85A"
			(at 149.86 95.758 0)
			(effects
				(font
					(size 1.27 1.27)
					(thickness 0.15)
				)
			)
		)
		(property "Manufacturer" "Murata"
			(at 161.29 110.49 0)
			(effects
				(font
					(size 1.27 1.27)
					(thickness 0.15)
				)
				(justify left bottom)
				(hide yes)
			)
		)
		(property "MPN" "LQW15AN2N4B00D"
			(at 161.29 113.03 0)
			(effects
				(font
					(size 1.27 1.27)
					(thickness 0.15)
				)
				(justify left bottom)
				(hide yes)
			)
		)
		(property "ISat" "0.85 A"
			(at 161.29 114.3 0)
			(effects
				(font
					(size 1.27 1.27)
				)
				(justify left)
				(hide yes)
			)
		)
		(property "IMax" "0.85 A"
			(at 161.29 118.11 0)
			(effects
				(font
					(size 1.27 1.27)
					(thickness 0.15)
				)
				(justify left bottom)
				(hide yes)
			)
		)
		(property "Size" "1.0x0.5"
			(at 161.29 120.65 0)
			(effects
				(font
					(size 1.27 1.27)
					(thickness 0.15)
				)
				(justify left bottom)
				(hide yes)
			)
		)
		(property "Author" "Antmicro"
			(at 161.29 123.19 0)
			(effects
				(font
					(size 1.27 1.27)
					(thickness 0.15)
				)
				(justify left bottom)
				(hide yes)
			)
		)
		(property "License" "Apache-2.0"
			(at 161.29 125.73 0)
			(effects
				(font
					(size 1.27 1.27)
					(thickness 0.15)
				)
				(justify left bottom)
				(hide yes)
			)
		)
		(pin "2"
		)
		(pin "1"
		)
		(instances
			(project ""
				(path ""
					(reference "L6")
					(unit 1)
				)
			)
			(project "thunderbolt-to-10gbe-adapter"
				(path ""
					(reference "L12")
					(unit 1)
				)
			)
		)
	)
	(symbol
		(lib_id "antmicropower:GND")
		(at 95.25 107.95 0)
		(unit 1)
		(exclude_from_sim no)
		(in_bom yes)
		(on_board yes)
		(dnp no)
		(property "Reference" "#PWR0434"
			(at 104.14 110.49 0)
			(effects
				(font
					(size 1.27 1.27)
					(thickness 0.15)
				)
				(justify left bottom)
				(hide yes)
			)
		)
		(property "Value" "GND"
			(at 95.25 111.76 0)
			(effects
				(font
					(size 1.27 1.27)
					(thickness 0.15)
				)
			)
		)
		(property "Footprint" ""
			(at 104.14 115.57 0)
			(effects
				(font
					(size 1.27 1.27)
					(thickness 0.15)
				)
				(justify left bottom)
				(hide yes)
			)
		)
		(property "Datasheet" ""
			(at 104.14 120.65 0)
			(effects
				(font
					(size 1.27 1.27)
					(thickness 0.15)
				)
				(justify left bottom)
				(hide yes)
			)
		)
		(property "Description" ""
			(at 95.25 107.95 0)
			(effects
				(font
					(size 1.27 1.27)
				)
				(hide yes)
			)
		)
		(property "Author" "Antmicro"
			(at 104.14 115.57 0)
			(effects
				(font
					(size 1.27 1.27)
					(thickness 0.15)
				)
				(justify left bottom)
				(hide yes)
			)
		)
		(property "License" "Apache-2.0"
			(at 104.14 118.11 0)
			(effects
				(font
					(size 1.27 1.27)
					(thickness 0.15)
				)
				(justify left bottom)
				(hide yes)
			)
		)
		(pin "1"
		)
		(instances
			(project "OCuLink to 10GbE adapter"
				(path ""
					(reference "#PWR073")
					(unit 1)
				)
			)
			(project "thunderbolt-to-10gbe-adapter"
				(path ""
					(reference "#PWR0434")
					(unit 1)
				)
			)
		)
	)
	(symbol
		(lib_id "antmicroCapacitors0402:C_1u_25V_0402")
		(at 176.53 105.41 90)
		(unit 1)
		(exclude_from_sim no)
		(in_bom yes)
		(on_board yes)
		(dnp no)
		(property "Reference" "C296"
			(at 178.562 101.6 90)
			(effects
				(font
					(size 1.27 1.27)
					(thickness 0.15)
				)
				(justify right)
			)
		)
		(property "Value" "C_1u_25V_0402"
			(at 186.69 85.09 0)
			(effects
				(font
					(size 1.27 1.27)
					(thickness 0.15)
				)
				(justify left bottom)
				(hide yes)
			)
		)
		(property "Footprint" "antmicro-footprints:C_0402_1005Metric"
			(at 189.23 85.09 0)
			(effects
				(font
					(size 1.27 1.27)
					(thickness 0.15)
				)
				(justify left bottom)
				(hide yes)
			)
		)
		(property "Datasheet" "https://www.murata.com/products/productdetail?partno=GRM155R61E105KE11%23"
			(at 191.77 85.09 0)
			(effects
				(font
					(size 1.27 1.27)
					(thickness 0.15)
				)
				(justify left bottom)
				(hide yes)
			)
		)
		(property "Description" "SMD Multilayer Ceramic Capacitor, 1 µF, 25 V, 0402 [1005 Metric], ± 10%, X5R, GRM Series"
			(at 176.53 105.41 0)
			(effects
				(font
					(size 1.27 1.27)
				)
				(hide yes)
			)
		)
		(property "MPN" "GRM155R61E105KE11J"
			(at 194.31 85.09 0)
			(effects
				(font
					(size 1.27 1.27)
					(thickness 0.15)
				)
				(justify left bottom)
				(hide yes)
			)
		)
		(property "Manufacturer" "Murata"
			(at 196.85 85.09 0)
			(effects
				(font
					(size 1.27 1.27)
					(thickness 0.15)
				)
				(justify left bottom)
				(hide yes)
			)
		)
		(property "License" "Apache-2.0"
			(at 199.39 85.09 0)
			(effects
				(font
					(size 1.27 1.27)
					(thickness 0.15)
				)
				(justify left bottom)
				(hide yes)
			)
		)
		(property "Author" "Antmicro"
			(at 201.93 85.09 0)
			(effects
				(font
					(size 1.27 1.27)
					(thickness 0.15)
				)
				(justify left bottom)
				(hide yes)
			)
		)
		(property "Val" "1u"
			(at 178.562 104.14 90)
			(effects
				(font
					(size 1.27 1.27)
					(thickness 0.15)
				)
				(justify right)
			)
		)
		(property "Voltage" "25V"
			(at 204.47 85.09 0)
			(effects
				(font
					(size 1.27 1.27)
				)
				(justify left bottom)
				(hide yes)
			)
		)
		(property "Dielectric" "X5R"
			(at 207.01 85.09 0)
			(effects
				(font
					(size 1.27 1.27)
				)
				(justify left bottom)
				(hide yes)
			)
		)
		(pin "1"
		)
		(pin "2"
		)
		(instances
			(project "OCuLink to 10GbE adapter"
				(path ""
					(reference "C57")
					(unit 1)
				)
			)
			(project "thunderbolt-to-10gbe-adapter"
				(path ""
					(reference "C296")
					(unit 1)
				)
			)
		)
	)
	(symbol
		(lib_id "antmicropower:GND")
		(at 71.12 107.95 0)
		(unit 1)
		(exclude_from_sim no)
		(in_bom yes)
		(on_board yes)
		(dnp no)
		(property "Reference" "#PWR0431"
			(at 80.01 110.49 0)
			(effects
				(font
					(size 1.27 1.27)
					(thickness 0.15)
				)
				(justify left bottom)
				(hide yes)
			)
		)
		(property "Value" "GND"
			(at 71.12 111.76 0)
			(effects
				(font
					(size 1.27 1.27)
					(thickness 0.15)
				)
			)
		)
		(property "Footprint" ""
			(at 80.01 115.57 0)
			(effects
				(font
					(size 1.27 1.27)
					(thickness 0.15)
				)
				(justify left bottom)
				(hide yes)
			)
		)
		(property "Datasheet" ""
			(at 80.01 120.65 0)
			(effects
				(font
					(size 1.27 1.27)
					(thickness 0.15)
				)
				(justify left bottom)
				(hide yes)
			)
		)
		(property "Description" ""
			(at 71.12 107.95 0)
			(effects
				(font
					(size 1.27 1.27)
				)
				(hide yes)
			)
		)
		(property "Author" "Antmicro"
			(at 80.01 115.57 0)
			(effects
				(font
					(size 1.27 1.27)
					(thickness 0.15)
				)
				(justify left bottom)
				(hide yes)
			)
		)
		(property "License" "Apache-2.0"
			(at 80.01 118.11 0)
			(effects
				(font
					(size 1.27 1.27)
					(thickness 0.15)
				)
				(justify left bottom)
				(hide yes)
			)
		)
		(pin "1"
		)
		(instances
			(project "OCuLink to 10GbE adapter"
				(path ""
					(reference "#PWR071")
					(unit 1)
				)
			)
			(project "thunderbolt-to-10gbe-adapter"
				(path ""
					(reference "#PWR0431")
					(unit 1)
				)
			)
		)
	)
	(symbol
		(lib_id "antmicroCapacitors0402:C_1u_25V_0402")
		(at 194.31 105.41 90)
		(unit 1)
		(exclude_from_sim no)
		(in_bom yes)
		(on_board yes)
		(dnp no)
		(property "Reference" "C300"
			(at 196.342 101.6 90)
			(effects
				(font
					(size 1.27 1.27)
					(thickness 0.15)
				)
				(justify right)
			)
		)
		(property "Value" "C_1u_25V_0402"
			(at 204.47 85.09 0)
			(effects
				(font
					(size 1.27 1.27)
					(thickness 0.15)
				)
				(justify left bottom)
				(hide yes)
			)
		)
		(property "Footprint" "antmicro-footprints:C_0402_1005Metric"
			(at 207.01 85.09 0)
			(effects
				(font
					(size 1.27 1.27)
					(thickness 0.15)
				)
				(justify left bottom)
				(hide yes)
			)
		)
		(property "Datasheet" "https://www.murata.com/products/productdetail?partno=GRM155R61E105KE11%23"
			(at 209.55 85.09 0)
			(effects
				(font
					(size 1.27 1.27)
					(thickness 0.15)
				)
				(justify left bottom)
				(hide yes)
			)
		)
		(property "Description" "SMD Multilayer Ceramic Capacitor, 1 µF, 25 V, 0402 [1005 Metric], ± 10%, X5R, GRM Series"
			(at 194.31 105.41 0)
			(effects
				(font
					(size 1.27 1.27)
				)
				(hide yes)
			)
		)
		(property "MPN" "GRM155R61E105KE11J"
			(at 212.09 85.09 0)
			(effects
				(font
					(size 1.27 1.27)
					(thickness 0.15)
				)
				(justify left bottom)
				(hide yes)
			)
		)
		(property "Manufacturer" "Murata"
			(at 214.63 85.09 0)
			(effects
				(font
					(size 1.27 1.27)
					(thickness 0.15)
				)
				(justify left bottom)
				(hide yes)
			)
		)
		(property "License" "Apache-2.0"
			(at 217.17 85.09 0)
			(effects
				(font
					(size 1.27 1.27)
					(thickness 0.15)
				)
				(justify left bottom)
				(hide yes)
			)
		)
		(property "Author" "Antmicro"
			(at 219.71 85.09 0)
			(effects
				(font
					(size 1.27 1.27)
					(thickness 0.15)
				)
				(justify left bottom)
				(hide yes)
			)
		)
		(property "Val" "1u"
			(at 196.342 104.14 90)
			(effects
				(font
					(size 1.27 1.27)
					(thickness 0.15)
				)
				(justify right)
			)
		)
		(property "Voltage" "25V"
			(at 222.25 85.09 0)
			(effects
				(font
					(size 1.27 1.27)
				)
				(justify left bottom)
				(hide yes)
			)
		)
		(property "Dielectric" "X5R"
			(at 224.79 85.09 0)
			(effects
				(font
					(size 1.27 1.27)
				)
				(justify left bottom)
				(hide yes)
			)
		)
		(pin "1"
		)
		(pin "2"
		)
		(instances
			(project ""
				(path ""
					(reference "C59")
					(unit 1)
				)
			)
			(project "thunderbolt-to-10gbe-adapter"
				(path ""
					(reference "C300")
					(unit 1)
				)
			)
		)
	)
	(symbol
		(lib_id "antmicropower:+1V8")
		(at 92.71 95.25 0)
		(unit 1)
		(exclude_from_sim no)
		(in_bom yes)
		(on_board yes)
		(dnp no)
		(property "Reference" "#PWR0433"
			(at 107.95 97.79 0)
			(effects
				(font
					(size 1.27 1.27)
					(thickness 0.15)
				)
				(justify left bottom)
				(hide yes)
			)
		)
		(property "Value" "+1V88_CT"
			(at 92.71 91.44 0)
			(effects
				(font
					(size 1.27 1.27)
					(thickness 0.15)
				)
			)
		)
		(property "Footprint" ""
			(at 107.95 102.87 0)
			(effects
				(font
					(size 1.27 1.27)
					(thickness 0.15)
				)
				(justify left bottom)
				(hide yes)
			)
		)
		(property "Datasheet" ""
			(at 107.95 105.41 0)
			(effects
				(font
					(size 1.27 1.27)
					(thickness 0.15)
				)
				(justify left bottom)
				(hide yes)
			)
		)
		(property "Description" ""
			(at 92.71 95.25 0)
			(effects
				(font
					(size 1.27 1.27)
				)
				(hide yes)
			)
		)
		(property "Author" "Antmicro"
			(at 107.95 100.33 0)
			(effects
				(font
					(size 1.27 1.27)
					(thickness 0.15)
				)
				(justify left bottom)
				(hide yes)
			)
		)
		(property "License" "Apache-2.0"
			(at 107.95 102.87 0)
			(effects
				(font
					(size 1.27 1.27)
					(thickness 0.15)
				)
				(justify left bottom)
				(hide yes)
			)
		)
		(pin "1"
		)
		(instances
			(project "OCuLink to 10GbE adapter"
				(path ""
					(reference "#PWR068")
					(unit 1)
				)
			)
			(project "thunderbolt-to-10gbe-adapter"
				(path ""
					(reference "#PWR0433")
					(unit 1)
				)
			)
		)
	)
	(symbol
		(lib_id "antmicroCapacitors0402:C_470p_0402")
		(at 233.68 238.76 90)
		(unit 1)
		(exclude_from_sim no)
		(in_bom yes)
		(on_board yes)
		(dnp no)
		(property "Reference" "C303"
			(at 235.712 234.95 90)
			(effects
				(font
					(size 1.27 1.27)
					(thickness 0.15)
				)
				(justify right)
			)
		)
		(property "Value" "C_470p_0402"
			(at 243.84 218.44 0)
			(effects
				(font
					(size 1.27 1.27)
					(thickness 0.15)
				)
				(justify left bottom)
				(hide yes)
			)
		)
		(property "Footprint" "antmicro-footprints:C_0402_1005Metric"
			(at 246.38 218.44 0)
			(effects
				(font
					(size 1.27 1.27)
					(thickness 0.15)
				)
				(justify left bottom)
				(hide yes)
			)
		)
		(property "Datasheet" "https://www.passivecomponent.com/wp-content/uploads/datasheet/WTC_MLCC_General_Purpose.pdf"
			(at 248.92 218.44 0)
			(effects
				(font
					(size 1.27 1.27)
					(thickness 0.15)
				)
				(justify left bottom)
				(hide yes)
			)
		)
		(property "Description" "SMD Multilayer Ceramic Capacitor, General Purpose, 470 pF, 25 V, 0402 [1005 Metric], ± 10%, X7R"
			(at 233.68 238.76 0)
			(effects
				(font
					(size 1.27 1.27)
				)
				(hide yes)
			)
		)
		(property "MPN" "0402B471K250CT"
			(at 251.46 218.44 0)
			(effects
				(font
					(size 1.27 1.27)
					(thickness 0.15)
				)
				(justify left bottom)
				(hide yes)
			)
		)
		(property "Manufacturer" "Walsin"
			(at 254 218.44 0)
			(effects
				(font
					(size 1.27 1.27)
					(thickness 0.15)
				)
				(justify left bottom)
				(hide yes)
			)
		)
		(property "License" "Apache-2.0"
			(at 256.54 218.44 0)
			(effects
				(font
					(size 1.27 1.27)
					(thickness 0.15)
				)
				(justify left bottom)
				(hide yes)
			)
		)
		(property "Author" "Antmicro"
			(at 259.08 218.44 0)
			(effects
				(font
					(size 1.27 1.27)
					(thickness 0.15)
				)
				(justify left bottom)
				(hide yes)
			)
		)
		(property "Val" "470p"
			(at 235.712 237.49 90)
			(effects
				(font
					(size 1.27 1.27)
					(thickness 0.15)
				)
				(justify right)
			)
		)
		(property "Voltage" "25V"
			(at 261.62 218.44 0)
			(effects
				(font
					(size 1.27 1.27)
				)
				(justify left bottom)
				(hide yes)
			)
		)
		(property "Dielectric" "X7R"
			(at 264.16 218.44 0)
			(effects
				(font
					(size 1.27 1.27)
				)
				(justify left bottom)
				(hide yes)
			)
		)
		(pin "2"
		)
		(pin "1"
		)
		(instances
			(project "OCuLink to 10GbE adapter"
				(path ""
					(reference "C60")
					(unit 1)
				)
			)
			(project "thunderbolt-to-10gbe-adapter"
				(path ""
					(reference "C303")
					(unit 1)
				)
			)
		)
	)
	(symbol
		(lib_id "antmicroCapacitors0402:C_1u_25V_0402")
		(at 167.64 241.3 90)
		(unit 1)
		(exclude_from_sim no)
		(in_bom yes)
		(on_board yes)
		(dnp no)
		(property "Reference" "C295"
			(at 169.672 237.49 90)
			(effects
				(font
					(size 1.27 1.27)
					(thickness 0.15)
				)
				(justify right)
			)
		)
		(property "Value" "C_1u_25V_0402"
			(at 177.8 220.98 0)
			(effects
				(font
					(size 1.27 1.27)
					(thickness 0.15)
				)
				(justify left bottom)
				(hide yes)
			)
		)
		(property "Footprint" "antmicro-footprints:C_0402_1005Metric"
			(at 180.34 220.98 0)
			(effects
				(font
					(size 1.27 1.27)
					(thickness 0.15)
				)
				(justify left bottom)
				(hide yes)
			)
		)
		(property "Datasheet" "https://www.murata.com/products/productdetail?partno=GRM155R61E105KE11%23"
			(at 182.88 220.98 0)
			(effects
				(font
					(size 1.27 1.27)
					(thickness 0.15)
				)
				(justify left bottom)
				(hide yes)
			)
		)
		(property "Description" "SMD Multilayer Ceramic Capacitor, 1 µF, 25 V, 0402 [1005 Metric], ± 10%, X5R, GRM Series"
			(at 167.64 241.3 0)
			(effects
				(font
					(size 1.27 1.27)
				)
				(hide yes)
			)
		)
		(property "MPN" "GRM155R61E105KE11J"
			(at 185.42 220.98 0)
			(effects
				(font
					(size 1.27 1.27)
					(thickness 0.15)
				)
				(justify left bottom)
				(hide yes)
			)
		)
		(property "Manufacturer" "Murata"
			(at 187.96 220.98 0)
			(effects
				(font
					(size 1.27 1.27)
					(thickness 0.15)
				)
				(justify left bottom)
				(hide yes)
			)
		)
		(property "License" "Apache-2.0"
			(at 190.5 220.98 0)
			(effects
				(font
					(size 1.27 1.27)
					(thickness 0.15)
				)
				(justify left bottom)
				(hide yes)
			)
		)
		(property "Author" "Antmicro"
			(at 193.04 220.98 0)
			(effects
				(font
					(size 1.27 1.27)
					(thickness 0.15)
				)
				(justify left bottom)
				(hide yes)
			)
		)
		(property "Val" "1u"
			(at 169.672 240.03 90)
			(effects
				(font
					(size 1.27 1.27)
					(thickness 0.15)
				)
				(justify right)
			)
		)
		(property "Voltage" "25V"
			(at 195.58 220.98 0)
			(effects
				(font
					(size 1.27 1.27)
				)
				(justify left bottom)
				(hide yes)
			)
		)
		(property "Dielectric" "X5R"
			(at 198.12 220.98 0)
			(effects
				(font
					(size 1.27 1.27)
				)
				(justify left bottom)
				(hide yes)
			)
		)
		(pin "1"
		)
		(pin "2"
		)
		(instances
			(project "OCuLink to 10GbE adapter"
				(path ""
					(reference "C64")
					(unit 1)
				)
			)
			(project "thunderbolt-to-10gbe-adapter"
				(path ""
					(reference "C295")
					(unit 1)
				)
			)
		)
	)
	(symbol
		(lib_id "antmicroCapacitors0402:C_100n_0402")
		(at 59.69 105.41 90)
		(unit 1)
		(exclude_from_sim no)
		(in_bom yes)
		(on_board yes)
		(dnp no)
		(property "Reference" "C288"
			(at 61.722 101.6 90)
			(effects
				(font
					(size 1.27 1.27)
					(thickness 0.15)
				)
				(justify right)
			)
		)
		(property "Value" "C_100n_0402"
			(at 82.55 90.17 0)
			(effects
				(font
					(size 1.27 1.27)
					(thickness 0.15)
				)
				(justify left bottom)
				(hide yes)
			)
		)
		(property "Footprint" "antmicro-footprints:C_0402_1005Metric"
			(at 85.09 90.17 0)
			(effects
				(font
					(size 1.27 1.27)
					(thickness 0.15)
				)
				(justify left bottom)
				(hide yes)
			)
		)
		(property "Datasheet" "https://www.murata.com/products/productdetail?partno=GRM155R61H104KE14%23"
			(at 87.63 90.17 0)
			(effects
				(font
					(size 1.27 1.27)
					(thickness 0.15)
				)
				(justify left bottom)
				(hide yes)
			)
		)
		(property "Description" "SMD Multilayer Ceramic Capacitor, 0.1 µF, 50 V, 0402 [1005 Metric], ± 10%, X5R, GRM Series"
			(at 59.69 105.41 0)
			(effects
				(font
					(size 1.27 1.27)
				)
				(hide yes)
			)
		)
		(property "MPN" "GRM155R61H104KE14D"
			(at 90.17 90.17 0)
			(effects
				(font
					(size 1.27 1.27)
					(thickness 0.15)
				)
				(justify left bottom)
				(hide yes)
			)
		)
		(property "Val" "100n"
			(at 61.722 104.14 90)
			(effects
				(font
					(size 1.27 1.27)
					(thickness 0.15)
				)
				(justify right)
			)
		)
		(property "Voltage" "50V"
			(at 69.85 90.17 0)
			(effects
				(font
					(size 1.27 1.27)
					(thickness 0.15)
				)
				(justify left bottom)
				(hide yes)
			)
		)
		(property "Dielectric" "X5R"
			(at 72.39 90.17 0)
			(effects
				(font
					(size 1.27 1.27)
					(thickness 0.15)
				)
				(justify left bottom)
				(hide yes)
			)
		)
		(property "Manufacturer" "Murata"
			(at 74.93 90.17 0)
			(effects
				(font
					(size 1.27 1.27)
					(thickness 0.15)
				)
				(justify left bottom)
				(hide yes)
			)
		)
		(property "License" "Apache-2.0"
			(at 77.47 90.17 0)
			(effects
				(font
					(size 1.27 1.27)
					(thickness 0.15)
				)
				(justify left bottom)
				(hide yes)
			)
		)
		(property "Author" "Antmicro"
			(at 80.01 90.17 0)
			(effects
				(font
					(size 1.27 1.27)
					(thickness 0.15)
				)
				(justify left bottom)
				(hide yes)
			)
		)
		(pin "2"
		)
		(pin "1"
		)
		(instances
			(project ""
				(path ""
					(reference "C51")
					(unit 1)
				)
			)
			(project "thunderbolt-to-10gbe-adapter"
				(path ""
					(reference "C288")
					(unit 1)
				)
			)
		)
	)
	(symbol
		(lib_id "antmicropower:GND")
		(at 185.42 107.95 0)
		(unit 1)
		(exclude_from_sim no)
		(in_bom yes)
		(on_board yes)
		(dnp no)
		(property "Reference" "#PWR0443"
			(at 194.31 110.49 0)
			(effects
				(font
					(size 1.27 1.27)
					(thickness 0.15)
				)
				(justify left bottom)
				(hide yes)
			)
		)
		(property "Value" "GND"
			(at 185.42 111.76 0)
			(effects
				(font
					(size 1.27 1.27)
					(thickness 0.15)
				)
			)
		)
		(property "Footprint" ""
			(at 194.31 115.57 0)
			(effects
				(font
					(size 1.27 1.27)
					(thickness 0.15)
				)
				(justify left bottom)
				(hide yes)
			)
		)
		(property "Datasheet" ""
			(at 194.31 120.65 0)
			(effects
				(font
					(size 1.27 1.27)
					(thickness 0.15)
				)
				(justify left bottom)
				(hide yes)
			)
		)
		(property "Description" ""
			(at 185.42 107.95 0)
			(effects
				(font
					(size 1.27 1.27)
				)
				(hide yes)
			)
		)
		(property "Author" "Antmicro"
			(at 194.31 115.57 0)
			(effects
				(font
					(size 1.27 1.27)
					(thickness 0.15)
				)
				(justify left bottom)
				(hide yes)
			)
		)
		(property "License" "Apache-2.0"
			(at 194.31 118.11 0)
			(effects
				(font
					(size 1.27 1.27)
					(thickness 0.15)
				)
				(justify left bottom)
				(hide yes)
			)
		)
		(pin "1"
		)
		(instances
			(project "OCuLink to 10GbE adapter"
				(path ""
					(reference "#PWR077")
					(unit 1)
				)
			)
			(project "thunderbolt-to-10gbe-adapter"
				(path ""
					(reference "#PWR0443")
					(unit 1)
				)
			)
		)
	)
	(symbol
		(lib_id "antmicropower:GND")
		(at 59.69 107.95 0)
		(unit 1)
		(exclude_from_sim no)
		(in_bom yes)
		(on_board yes)
		(dnp no)
		(property "Reference" "#PWR0430"
			(at 68.58 110.49 0)
			(effects
				(font
					(size 1.27 1.27)
					(thickness 0.15)
				)
				(justify left bottom)
				(hide yes)
			)
		)
		(property "Value" "GND"
			(at 59.69 111.76 0)
			(effects
				(font
					(size 1.27 1.27)
					(thickness 0.15)
				)
			)
		)
		(property "Footprint" ""
			(at 68.58 115.57 0)
			(effects
				(font
					(size 1.27 1.27)
					(thickness 0.15)
				)
				(justify left bottom)
				(hide yes)
			)
		)
		(property "Datasheet" ""
			(at 68.58 120.65 0)
			(effects
				(font
					(size 1.27 1.27)
					(thickness 0.15)
				)
				(justify left bottom)
				(hide yes)
			)
		)
		(property "Description" ""
			(at 59.69 107.95 0)
			(effects
				(font
					(size 1.27 1.27)
				)
				(hide yes)
			)
		)
		(property "Author" "Antmicro"
			(at 68.58 115.57 0)
			(effects
				(font
					(size 1.27 1.27)
					(thickness 0.15)
				)
				(justify left bottom)
				(hide yes)
			)
		)
		(property "License" "Apache-2.0"
			(at 68.58 118.11 0)
			(effects
				(font
					(size 1.27 1.27)
					(thickness 0.15)
				)
				(justify left bottom)
				(hide yes)
			)
		)
		(pin "1"
		)
		(instances
			(project "OCuLink to 10GbE adapter"
				(path ""
					(reference "#PWR070")
					(unit 1)
				)
			)
			(project "thunderbolt-to-10gbe-adapter"
				(path ""
					(reference "#PWR0430")
					(unit 1)
				)
			)
		)
	)
	(symbol
		(lib_id "antmicroFerriteBeadsandChips:FB_33Z_3A_Murata-BLM18PG_0603")
		(at 76.2 97.79 0)
		(unit 1)
		(exclude_from_sim no)
		(in_bom yes)
		(on_board yes)
		(dnp no)
		(fields_autoplaced yes)
		(property "Reference" "FB9"
			(at 78.7019 91.44 0)
			(effects
				(font
					(size 1.27 1.27)
					(thickness 0.15)
				)
			)
		)
		(property "Value" "FB_33Z_3A_Murata-BLM18PG_0603"
			(at 90.17 100.33 0)
			(effects
				(font
					(size 1.27 1.27)
					(thickness 0.15)
				)
				(justify left bottom)
				(hide yes)
			)
		)
		(property "Footprint" "antmicro-footprints:FB_0603_1608Metric"
			(at 90.17 105.41 0)
			(effects
				(font
					(size 1.27 1.27)
					(thickness 0.15)
				)
				(justify left bottom)
				(hide yes)
			)
		)
		(property "Datasheet" "https://www.murata.com/products/productdata/8796737273886/QNFA9101.pdf?1649080818000"
			(at 90.17 107.95 0)
			(effects
				(font
					(size 1.27 1.27)
					(thickness 0.15)
				)
				(justify left bottom)
				(hide yes)
			)
		)
		(property "Description" "Ferrite Bead, 0603 [1608 Metric], 33 ohm, 3 A, BLM18PG, 0.025 ohm, ± 25%, DC power line"
			(at 76.2 97.79 0)
			(effects
				(font
					(size 1.27 1.27)
				)
				(hide yes)
			)
		)
		(property "Val" "33Z/3A"
			(at 78.7019 93.98 0)
			(effects
				(font
					(size 1.27 1.27)
				)
			)
		)
		(property "MPN" "BLM18PG330SH1D"
			(at 90.17 110.49 0)
			(effects
				(font
					(size 1.27 1.27)
					(thickness 0.15)
				)
				(justify left bottom)
				(hide yes)
			)
		)
		(property "Manufacturer" "Murata"
			(at 90.17 113.03 0)
			(effects
				(font
					(size 1.27 1.27)
					(thickness 0.15)
				)
				(justify left bottom)
				(hide yes)
			)
		)
		(property "Current" ""
			(at 96.52 120.65 0)
			(effects
				(font
					(size 1.27 1.27)
					(thickness 0.15)
				)
				(justify left bottom)
				(hide yes)
			)
		)
		(property "Author" "Antmicro"
			(at 90.17 115.57 0)
			(effects
				(font
					(size 1.27 1.27)
					(thickness 0.15)
				)
				(justify left bottom)
				(hide yes)
			)
		)
		(property "License" "Apache-2.0"
			(at 90.17 118.11 0)
			(effects
				(font
					(size 1.27 1.27)
					(thickness 0.15)
				)
				(justify left bottom)
				(hide yes)
			)
		)
		(pin "2"
		)
		(pin "1"
		)
		(instances
			(project ""
				(path ""
					(reference "FB1")
					(unit 1)
				)
			)
			(project "thunderbolt-to-10gbe-adapter"
				(path ""
					(reference "FB9")
					(unit 1)
				)
			)
		)
	)
	(symbol
		(lib_id "antmicroResistors0402:R_220R_0402")
		(at 259.08 228.6 0)
		(unit 1)
		(exclude_from_sim no)
		(in_bom yes)
		(on_board yes)
		(dnp no)
		(property "Reference" "R215"
			(at 259.08 227.33 0)
			(effects
				(font
					(size 1.27 1.27)
					(thickness 0.15)
				)
				(justify right)
			)
		)
		(property "Value" "R_220R_0402"
			(at 279.4 241.3 0)
			(effects
				(font
					(size 1.27 1.27)
					(thickness 0.15)
				)
				(justify left bottom)
				(hide yes)
			)
		)
		(property "Footprint" "antmicro-footprints:R_0402_1005Metric"
			(at 279.4 243.84 0)
			(effects
				(font
					(size 1.27 1.27)
					(thickness 0.15)
				)
				(justify left bottom)
				(hide yes)
			)
		)
		(property "Datasheet" "https://www.bourns.com/docs/product-datasheets/cr.pdf"
			(at 279.4 246.38 0)
			(effects
				(font
					(size 1.27 1.27)
					(thickness 0.15)
				)
				(justify left bottom)
				(hide yes)
			)
		)
		(property "Description" "SMD Chip Resistor, 220 ohm, ± 1%, 62.5 mW, 0402 [1005 Metric], Thick Film, General Purpose"
			(at 259.08 228.6 0)
			(effects
				(font
					(size 1.27 1.27)
				)
				(hide yes)
			)
		)
		(property "MPN" "CR0402-FX-2200GLF"
			(at 279.4 248.92 0)
			(effects
				(font
					(size 1.27 1.27)
					(thickness 0.15)
				)
				(justify left bottom)
				(hide yes)
			)
		)
		(property "Manufacturer" "Bourns"
			(at 279.4 251.46 0)
			(effects
				(font
					(size 1.27 1.27)
					(thickness 0.15)
				)
				(justify left bottom)
				(hide yes)
			)
		)
		(property "License" "Apache-2.0"
			(at 279.4 254 0)
			(effects
				(font
					(size 1.27 1.27)
					(thickness 0.15)
				)
				(justify left bottom)
				(hide yes)
			)
		)
		(property "Author" "Antmicro"
			(at 279.4 256.54 0)
			(effects
				(font
					(size 1.27 1.27)
					(thickness 0.15)
				)
				(justify left bottom)
				(hide yes)
			)
		)
		(property "Val" "220R"
			(at 264.16 227.33 0)
			(effects
				(font
					(size 1.27 1.27)
					(thickness 0.15)
				)
				(justify left)
			)
		)
		(property "Tolerance" "1%"
			(at 279.4 238.76 0)
			(effects
				(font
					(size 1.27 1.27)
				)
				(justify left bottom)
				(hide yes)
			)
		)
		(pin "1"
		)
		(pin "2"
		)
		(instances
			(project "OCuLink to 10GbE adapter"
				(path ""
					(reference "R41")
					(unit 1)
				)
			)
			(project "thunderbolt-to-10gbe-adapter"
				(path ""
					(reference "R215")
					(unit 1)
				)
			)
		)
	)
	(symbol
		(lib_id "antmicropower:GND")
		(at 167.64 243.84 0)
		(unit 1)
		(exclude_from_sim no)
		(in_bom yes)
		(on_board yes)
		(dnp no)
		(property "Reference" "#PWR0440"
			(at 176.53 246.38 0)
			(effects
				(font
					(size 1.27 1.27)
					(thickness 0.15)
				)
				(justify left bottom)
				(hide yes)
			)
		)
		(property "Value" "GND"
			(at 167.64 247.65 0)
			(effects
				(font
					(size 1.27 1.27)
					(thickness 0.15)
				)
			)
		)
		(property "Footprint" ""
			(at 176.53 251.46 0)
			(effects
				(font
					(size 1.27 1.27)
					(thickness 0.15)
				)
				(justify left bottom)
				(hide yes)
			)
		)
		(property "Datasheet" ""
			(at 176.53 256.54 0)
			(effects
				(font
					(size 1.27 1.27)
					(thickness 0.15)
				)
				(justify left bottom)
				(hide yes)
			)
		)
		(property "Description" ""
			(at 167.64 243.84 0)
			(effects
				(font
					(size 1.27 1.27)
				)
				(hide yes)
			)
		)
		(property "Author" "Antmicro"
			(at 176.53 251.46 0)
			(effects
				(font
					(size 1.27 1.27)
					(thickness 0.15)
				)
				(justify left bottom)
				(hide yes)
			)
		)
		(property "License" "Apache-2.0"
			(at 176.53 254 0)
			(effects
				(font
					(size 1.27 1.27)
					(thickness 0.15)
				)
				(justify left bottom)
				(hide yes)
			)
		)
		(pin "1"
		)
		(instances
			(project "OCuLink to 10GbE adapter"
				(path ""
					(reference "#PWR084")
					(unit 1)
				)
			)
			(project "thunderbolt-to-10gbe-adapter"
				(path ""
					(reference "#PWR0440")
					(unit 1)
				)
			)
		)
	)
	(symbol
		(lib_id "antmicroResistors0402:R_220R_0402")
		(at 259.08 92.71 0)
		(unit 1)
		(exclude_from_sim no)
		(in_bom yes)
		(on_board yes)
		(dnp no)
		(property "Reference" "R212"
			(at 259.08 91.44 0)
			(effects
				(font
					(size 1.27 1.27)
					(thickness 0.15)
				)
				(justify right)
			)
		)
		(property "Value" "R_220R_0402"
			(at 279.4 105.41 0)
			(effects
				(font
					(size 1.27 1.27)
					(thickness 0.15)
				)
				(justify left bottom)
				(hide yes)
			)
		)
		(property "Footprint" "antmicro-footprints:R_0402_1005Metric"
			(at 279.4 107.95 0)
			(effects
				(font
					(size 1.27 1.27)
					(thickness 0.15)
				)
				(justify left bottom)
				(hide yes)
			)
		)
		(property "Datasheet" "https://www.bourns.com/docs/product-datasheets/cr.pdf"
			(at 279.4 110.49 0)
			(effects
				(font
					(size 1.27 1.27)
					(thickness 0.15)
				)
				(justify left bottom)
				(hide yes)
			)
		)
		(property "Description" "SMD Chip Resistor, 220 ohm, ± 1%, 62.5 mW, 0402 [1005 Metric], Thick Film, General Purpose"
			(at 259.08 92.71 0)
			(effects
				(font
					(size 1.27 1.27)
				)
				(hide yes)
			)
		)
		(property "MPN" "CR0402-FX-2200GLF"
			(at 279.4 113.03 0)
			(effects
				(font
					(size 1.27 1.27)
					(thickness 0.15)
				)
				(justify left bottom)
				(hide yes)
			)
		)
		(property "Manufacturer" "Bourns"
			(at 279.4 115.57 0)
			(effects
				(font
					(size 1.27 1.27)
					(thickness 0.15)
				)
				(justify left bottom)
				(hide yes)
			)
		)
		(property "License" "Apache-2.0"
			(at 279.4 118.11 0)
			(effects
				(font
					(size 1.27 1.27)
					(thickness 0.15)
				)
				(justify left bottom)
				(hide yes)
			)
		)
		(property "Author" "Antmicro"
			(at 279.4 120.65 0)
			(effects
				(font
					(size 1.27 1.27)
					(thickness 0.15)
				)
				(justify left bottom)
				(hide yes)
			)
		)
		(property "Val" "220R"
			(at 264.16 91.44 0)
			(effects
				(font
					(size 1.27 1.27)
					(thickness 0.15)
				)
				(justify left)
			)
		)
		(property "Tolerance" "1%"
			(at 279.4 102.87 0)
			(effects
				(font
					(size 1.27 1.27)
				)
				(justify left bottom)
				(hide yes)
			)
		)
		(pin "1"
		)
		(pin "2"
		)
		(instances
			(project "OCuLink to 10GbE adapter"
				(path ""
					(reference "R38")
					(unit 1)
				)
			)
			(project "thunderbolt-to-10gbe-adapter"
				(path ""
					(reference "R212")
					(unit 1)
				)
			)
		)
	)
)
